5
5
4
4
3
3
2
2
1
1
D D
C C
B B
A A
PCB P/N: 15669
Version: 1
Project Code: BPD00Q010001
Lightning PDPB PVT 
Title 
Size Document Number Rev
Date: Sheet 
of 
Lightning_PDPB 
1
COVER PAGE 
A4 
1 28Thursday, March 02, 2017 
Wiwynn 
H/W R&D Dept. II 
8F,90,Sec. 1,Hsin Tai Wu Rd, 
Hsichih, Taipei Hsien 221, Taiwan, R.O.C
Title 
Size Document Number Rev
Date: Sheet 
of 
Lightning_PDPB 
1
COVER PAGE 
A4 
1 28Thursday, March 02, 2017 
Wiwynn 
H/W R&D Dept. II 
8F,90,Sec. 1,Hsin Tai Wu Rd, 
Hsichih, Taipei Hsien 221, Taiwan, R.O.C
Title 
Size Document Number Rev
Date: Sheet 
of 
Lightning_PDPB 
1
COVER PAGE 
A4 
1 28Thursday, March 02, 2017 
Wiwynn 
H/W R&D Dept. II 
8F,90,Sec. 1,Hsin Tai Wu Rd, 
Hsichih, Taipei Hsien 221, Taiwan, R.O.C



5
5
4
4
3
3
2
2
1
1
D D
C C
B B
A A
TABLE OF CONTENTS
12 15 16 17 20 2113 14 18 1903 04 05 08 111002 0706 0901
PAGE TITLE PAGE
PAGE
PAGE TITLE
COVER PAGETABLE OF CONTENTS
22
BLOCK DIAGRAMPOWER MAPSTACKUPI2C TOPOLOGYCLOCK TOPOLOGY SSD CNs 0-1 CARD EDGE CONN_1CARD EDGE CONN_2STRADDLE CONNI2C_DEVICESI2C_BUS_SWITCHI2C_CLK_BUFFER_1I2C_CLK_BUFFER_2
P3V3_TPS53312SCREWCHANGE LIST_1
24 25 26 27
SSD CNs 2-3SSD CNs 4-5SSD CNs 6-7SSD CNs 8-9SSD CNs 10-11SSD CNs 12-13SSD CNs 14
CHANGE LIST_2CHANGE LIST_3
23 28 CHANGE LIST_4
Title 
Size Document Number Rev
Date: Sheet 
of 
Lightning_PDPB 
1
TABLE OF CONTENTS 
A4 
2 28Thursday, March 02, 2017 
Wiwynn 
H/W R&D Dept. II 
8F,90,Sec. 1,Hsin Tai Wu Rd, 
Hsichih, Taipei Hsien 221, Taiwan, R.O.C
Title 
Size Document Number Rev
Date: Sheet 
of 
Lightning_PDPB 
1
TABLE OF CONTENTS 
A4 
2 28Thursday, March 02, 2017 
Wiwynn 
H/W R&D Dept. II 
8F,90,Sec. 1,Hsin Tai Wu Rd, 
Hsichih, Taipei Hsien 221, Taiwan, R.O.C
Title 
Size Document Number Rev
Date: Sheet 
of 
Lightning_PDPB 
1
TABLE OF CONTENTS 
A4 
2 28Thursday, March 02, 2017 
Wiwynn 
H/W R&D Dept. II 
8F,90,Sec. 1,Hsin Tai Wu Rd, 
Hsichih, Taipei Hsien 221, Taiwan, R.O.C



5
5
4
4
3
3
2
2
1
1
D D
C C
B B
A A
Block Diagram 
Title 
Size Document Number Rev
Date: Sheet 
of 
Lightning_PDPB 1
BLOCK DIAGRAM 
A4 
3 28Thursday, March 02, 2017 
Wiwynn 
H/W R&D Dept. II 
8F,90,Sec. 1,Hsin Tai Wu Rd, 
Hsichih, Taipei Hsien 221, Taiwan, R.O.C
Title 
Size Document Number Rev
Date: Sheet 
of 
Lightning_PDPB 1
BLOCK DIAGRAM 
A4 
3 28Thursday, March 02, 2017 
Wiwynn 
H/W R&D Dept. II 
8F,90,Sec. 1,Hsin Tai Wu Rd, 
Hsichih, Taipei Hsien 221, Taiwan, R.O.C
Title 
Size Document Number Rev
Date: Sheet 
of 
Lightning_PDPB 1
BLOCK DIAGRAM 
A4 
3 28Thursday, March 02, 2017 
Wiwynn 
H/W R&D Dept. II 
8F,90,Sec. 1,Hsin Tai Wu Rd, 
Hsichih, Taipei Hsien 221, Taiwan, R.O.C



5
5
4
4
3
3
2
2
1
1
D D
C C
B B
A A
CARD EDGE CONN 
J17 
 Power CONN 
Sheet 16~17 
NOPOP=no populated
562R2F-GP 
562 = 562 ohm, (2K2R means 2.2K ohm)
2 = size 0402 
F = 1% tolerance 
GP= Green Part (RoHS) 
Wiwynn RC size code as below: 
1 = 0201 
2= 0402 
3= 0603 
5= 0805 
6= 1206 
Wiwynn R tolerance code as below: 
D=0.5% 
F= 1% 
J= 5% 
SCD1U10V2KX-5GP 
D1U = 0.1uF (2D2U means 2.2uF) 
10Voltage (6D3V means 6.3V) 
2 = size 0402, K tolerance 
K=tolerance 
[Wiwynn C code as below:] 
G=2% 
J=5% 
K=10% 
M=20% 
X=temp characteristics 
[(RoHS) Wiwynn C Series/Temp] 
N=NPO 
X=X7R/X5R 
Y=Y5V 
-5=different symbol/customer 
GP= Green Part (RoHS) 
EEPROM 
P3V3 
12V 
J18 
U50 U53   VOL 
SENSOR 
J19 
CN7 
 CLK 
Buffer 
EU1 
EU2 
EU3 
EU4 
U47 
U48 
U49 
U51 
EU16 
EU17 
SWITCH 
(PCA9547) 
 TEMP 
SENSOR 
Sheet 8~15 
SSD CNs 0~14 
PU2  P3V3 
TPS53312 
(0.015A for U.2)  
(0.728A for M.2) 
(0.44A) (0.2A) LED 
(0.1343A) (300uA) (5mA) 
Sheet 19 Sheet 21~22 Sheet 20 
Sheet 23 
Pull High 
(0.1495A) 
Sheet 8~15 Sheet 19 Sheet 19 
18.45A=>1.23Ax15 pcs SSD 
(1.23A/Intel SSD) J100,J1~J14 
(1.64mA) 
LED100 
LED1 ~14 
POWER MAP 
(15A) 
PMC PEB OCP:10.5A 
Sheet 18 
(0.94629A for U.2) 
(34.39A for U.2 SSD)  
(0.93129A) 
(1.65929A for M.2) 
Title 
Size Document Number Rev
Date: Sheet 
of 
Lightning_PDPB 
1
POWER MAP 
A3 
4 28Friday, March 10, 2017 
Wiwynn 
H/W R&D Dept. II 
8F,90,Sec. 1,Hsin Tai Wu Rd, 
Hsichih, Taipei Hsien 221, Taiwan, R.O.C
Title 
Size Document Number Rev
Date: Sheet 
of 
Lightning_PDPB 
1
POWER MAP 
A3 
4 28Friday, March 10, 2017 
Wiwynn 
H/W R&D Dept. II 
8F,90,Sec. 1,Hsin Tai Wu Rd, 
Hsichih, Taipei Hsien 221, Taiwan, R.O.C
Title 
Size Document Number Rev
Date: Sheet 
of 
Lightning_PDPB 
1
POWER MAP 
A3 
4 28Friday, March 10, 2017 
Wiwynn 
H/W R&D Dept. II 
8F,90,Sec. 1,Hsin Tai Wu Rd, 
Hsichih, Taipei Hsien 221, Taiwan, R.O.C



5
5
4
4
3
3
2
2
1
1
D D
C C
B B
A A
STACKUP 
Title 
Size Document Number Rev
Date: Sheet 
of 
Lightning_PDPB 1
STACKUP 
A2 
5 28Friday, March 10, 2017 
Wiwynn 
H/W R&D Dept. II 
8F,90,Sec. 1,Hsin Tai Wu Rd, 
Hsichih, Taipei Hsien 221, Taiwan, R.O.C
Title 
Size Document Number Rev
Date: Sheet 
of 
Lightning_PDPB 1
STACKUP 
A2 
5 28Friday, March 10, 2017 
Wiwynn 
H/W R&D Dept. II 
8F,90,Sec. 1,Hsin Tai Wu Rd, 
Hsichih, Taipei Hsien 221, Taiwan, R.O.C
Title 
Size Document Number Rev
Date: Sheet 
of 
Lightning_PDPB 1
STACKUP 
A2 
5 28Friday, March 10, 2017 
Wiwynn 
H/W R&D Dept. II 
8F,90,Sec. 1,Hsin Tai Wu Rd, 
Hsichih, Taipei Hsien 221, Taiwan, R.O.C



5
5
4
4
3
3
2
2
1
1
D D
C C
B B
A A
BMC 
SWITCH_1 
(PCA9547) 
Cload 19 pF 
 VOLTAGE SENSOR 
EEPROM 
 TEMP SENSOR_2 U47 Cload:3 pF 
U48 Cload:3 pF  TEMP SENSOR_3 
U49 Cload:3 pF  TEMP SENSOR_4 
 TEMP SENSOR_1 U51 Cload:3 pF 
EU1  CLK Buffer_1 
 Cload 5 pF 
EU2 
U50 Cload:10 pF 
Address:0x92 
Address:0x94 
Address:0x96 
Address:0x98 
SWITCH_2 
(PCA9547) 
Cload:19 pF 
SSD SMBUS 
SSD:0,1,2,5,6,7,10,11 
SSD SMBUS 
SSD:3,4,8,9,12,13,14 EU17 
EU16 
Address:0xA2 
Address:0x90 
  I2C 
BUFFER 
  I2C 
BUFFER 
  I2C 
BUFFER 
AST2400 
Address:0xCE 
Address:0xDE 
Address:0xE4 
Address:0xD8 
Address:0xCA 
Address:0xE2 
I2C_8 
I2C_9 
I2C_B 
SAS_I2C_B_BUF_SCL_R 
BMC_I2C_SCL_BUF_8 
PEB 
PDPB 
PTB 
  I2C 
BUFFER 
I2C_C 
SAS_I2C_B_BUF_SDA_R 
BMC_I2C_SDA_BUF_8 
BMC_I2C_SCL_BUF_9 
BMC_I2C_SDA_BUF_9 
SAS_I2C_C_BUF_SCL_R 
SAS_I2C_C_BUF_SDA_R 
P3V3 
4.7K 
P3V3 
4.7K 
P3V3 
4.7K 
P3V3 
4.7K 
NOPOP 
NOPOP 
NOPOP 
NOPOP 
I2C TOPOLOGY 
U53 Cload:10 pF 
TMP SENSOR 
Address: 0x98 
M.2 
U1 
 CLK Buffer_2 
 Cload 5 pF 
 CLK Buffer_3 
 Cload 5 pF EU3 
 CLK Buffer_4 
 Cload 5 pF EU4 M.2 
U1 
TMP SENSOR 
Address: 0x98 
U4 Address: 0xE6 
SWITCH 
U4 
SWITCH 
Address: 0xE6 
Title 
Size Document Number Rev 
Date: Sheet 
of 
Lightning_PDPB 
1
I2C TOPOLOGY 
C
6 28 Friday, March 10, 2017 
Wiwynn 
H/W R&D Dept. II 
8F,90,Sec. 1,Hsin Tai Wu Rd, 
Hsichih, Taipei Hsien 221, Taiwan, R.O.C 
Title 
Size Document Number Rev 
Date: Sheet 
of 
Lightning_PDPB 
1
I2C TOPOLOGY 
C
6 28 Friday, March 10, 2017 
Wiwynn 
H/W R&D Dept. II 
8F,90,Sec. 1,Hsin Tai Wu Rd, 
Hsichih, Taipei Hsien 221, Taiwan, R.O.C 
Title 
Size Document Number Rev 
Date: Sheet 
of 
Lightning_PDPB 
1
I2C TOPOLOGY 
C
6 28 Friday, March 10, 2017 
Wiwynn 
H/W R&D Dept. II 
8F,90,Sec. 1,Hsin Tai Wu Rd, 
Hsichih, Taipei Hsien 221, Taiwan, R.O.C 



5
5
4
4
3
3
2
2
1
1
D D
C C
B B
A A
CLOCK TOPOLOGY 
Title 
Size Document Number Rev
Date: Sheet 
of 
Lightning_PDPB 
1
CLOCK TOPOLOGY 
A3 
7 28Thursday, March 02, 2017 
Wiwynn 
H/W R&D Dept. II 
8F,90,Sec. 1,Hsin Tai Wu Rd, 
Hsichih, Taipei Hsien 221, Taiwan, R.O.C
Title 
Size Document Number Rev
Date: Sheet 
of 
Lightning_PDPB 
1
CLOCK TOPOLOGY 
A3 
7 28Thursday, March 02, 2017 
Wiwynn 
H/W R&D Dept. II 
8F,90,Sec. 1,Hsin Tai Wu Rd, 
Hsichih, Taipei Hsien 221, Taiwan, R.O.C
Title 
Size Document Number Rev
Date: Sheet 
of 
Lightning_PDPB 
1
CLOCK TOPOLOGY 
A3 
7 28Thursday, March 02, 2017 
Wiwynn 
H/W R&D Dept. II 
8F,90,Sec. 1,Hsin Tai Wu Rd, 
Hsichih, Taipei Hsien 221, Taiwan, R.O.C



5
5
4
4
3
3
2
2
1
1
D D
C C
B B
A A
SSD0 
SSD1 
Close to 
Connect 
Close to 
Connect 
Close to 
EU1 
Close to 
EU1 
N-Channel 
N-Channel 
ID=-9A 
RDS(on) 
=20m ohm 
P-Channel 
Blue 
Red 
Close to 
EU1 
Close to 
EU1 
N-Channel 
Blue 
Red 
ID=-9A 
RDS(on) 
=20m ohm 
P-Channel 
N-Channel 
22U 
1206 
X6S 
22U 
1206 
X6S 
0.1U 
0603 
X7R 
0.01U 
0402 
X7R 
22U 
1206 
X6S 
0.1U 
0603 
X7R 
22U 
1206 
X6S 
0.01U 
0402 
X7R 
PVT 
20161102 
SSD0_CLK0_OE_n 
SSD_PRSNT_NET0 
SSD_ACT_DR0 
SSD_ACT_DR1 
SSD1_CLK0_OE_n 
SSD_PRSNT_NET1 
SCL_DR0_R 
SDA_DR0_R 
SCL_DR1_R 
SDA_DR1_R 
DUALPORTEN#0 
DUALPORTEN#1 
12V_PRECH_SSD0 
12V_PRECH_SSD1 
SSD0_CLK0_OE_n 
ATTN_LED_DR0_AND 
SSD_PRSNT_NET0 
SSD_ACT_DR0 
SW_SSD0_N 
SSD0_PWREN_R SSD0_PWREN 
P12V_MOST0_GATE 
P12V_MOST0_GATE_D 
SW_SSD0_R 
SSD0_CLK0_OE_R_n 
ATTN_LED_DR0_R 
SSD0_CLK0_OE_MOS_n 
SSD_ACT_DR0_R 
ATTN_LED_DR0_MOS_N 
SSD_ACT_DR0_MOS_N 
DRV_ATTN_0 
SSD1_CLK0_OE_n 
ATTN_LED_DR1_AND_R 
SSD_ACT_DR1 
SSD1_PWREN_R SSD1_PWREN 
P12V_MOST1_GATE 
P12V_MOST1_GATE_D 
SSD1_CLK0_OE_R_n 
ATTN_LED_DR1_R 
SSD1_CLK0_OE_MOS_n 
SSD_ACT_DR1_R 
ATTN_LED_DR1_MOS_N 
SSD_ACT_DR1_MOS_N 
DRV_ATTN_1 
SW_SSD1_N 
SW_SSD1_R 
SSD_PRSNT_NET1 
DRV_ACT_0 
DRV_ACT_1 
ATTN_LED_DR1_AND 
ATTN_LED_DR0_AND_R 
P3V3 
P12V_SSD1 
P3V3 
P12V_SSD0 
P3V3 
P12V_SSD0 
P3V3 
P12V_SSD1 
P3V3 
P3V3 
P3V3 P3V3 
P3V3 P12V P12V_SSD0 
P12V P12V_SSD0 
P12V 
P3V3 
P3V3 P3V3 
P3V3 
P3V3 
P3V3 
P12V P12V_SSD1 
P3V3 P3V3 
P3V3 
P3V3 P12V_SSD1 P12V P12V 
P3V3 
P12V 
P12V 
P3V3 
P3V3 
P3V3 
P3V3 
P3V3 
P3V3 
PE_CLK100M_dr0_2_p 21 
PE_CLK100M_dr0_2_n 21 
SSD0_PERST_N 16 
PE_TX1_DR0_p 16 
PE_TX1_DR0_n 16 
PE_CLK100M_dr0_1_p 21 
PE_CLK100M_dr0_1_n 21 
PE_RX1_DR0_n 16
PE_RX1_DR0_p 16
PE_TX2_DR0_n 16 
PE_TX2_DR0_p 16 
PE_RX2_DR0_n 16
PE_RX2_DR0_p 16
PE_TX3_DR0_p 16 
PE_TX3_DR0_n 16 
PE_RX3_DR0_p 16
PE_RX3_DR0_n 16
PE_TX4_DR0_n 16 
PE_TX4_DR0_p 16 
SDA_DR0 20
SCL_DR0 20
PE_RX4_DR0_p 16
PE_RX4_DR0_n 16
PE_RX1_DR1_n 16
PE_RX1_DR1_p 16
PE_TX3_DR1_p 16 
PE_TX3_DR1_n 16 
SDA_DR1 20
SCL_DR1 20
PE_RX4_DR1_p 16
PE_RX4_DR1_n 16
PE_RX3_DR1_p 16
PE_RX3_DR1_n 16
PE_CLK100M_dr1_2_p 21 
PE_CLK100M_dr1_2_n 21 
PE_TX2_DR1_n 16 
PE_TX2_DR1_p 16 
SSD1_PERST_N 16 
PE_TX1_DR1_p 16 
PE_TX1_DR1_n 16 
PE_CLK100M_dr1_1_p 21 
PE_CLK100M_dr1_1_n 21 
PE_RX2_DR1_n 16
PE_RX2_DR1_p 16
PE_TX4_DR1_n 16 
PE_TX4_DR1_p 16 
SSD0_CLK0_OE_R_n 16,21 
SSD0_PWREN 16 
SSD_PRSNT0 21 
ATTN_LED_DR0_N 8,16 
ATTN_LED_DR0_N 8,16 
SSD1_CLK0_OE_R_n 16,21 
ATTN_LED_DR1_N 8,16 
ATTN_LED_DR1_N 8,16 
SSD1_PWREN 16 
SSD_PRSNT1 21 
Title 
Size Document Number Rev
Date: Sheet 
of 
Lightning_PDPB 
1
SSD CNs 0-1 
A2 
8 28Thursday, March 09, 2017 
Wiwynn 
H/W R&D Dept. II 
8F,90,Sec. 1,Hsin Tai Wu Rd, 
Hsichih, Taipei Hsien 221, Taiwan, R.O.C
Title 
Size Document Number Rev
Date: Sheet 
of 
Lightning_PDPB 
1
SSD CNs 0-1 
A2 
8 28Thursday, March 09, 2017 
Wiwynn 
H/W R&D Dept. II 
8F,90,Sec. 1,Hsin Tai Wu Rd, 
Hsichih, Taipei Hsien 221, Taiwan, R.O.C
Title 
Size Document Number Rev
Date: Sheet 
of 
Lightning_PDPB 
1
SSD CNs 0-1 
A2 
8 28Thursday, March 09, 2017 
Wiwynn 
H/W R&D Dept. II 
8F,90,Sec. 1,Hsin Tai Wu Rd, 
Hsichih, Taipei Hsien 221, Taiwan, R.O.C
R9783 
0R2J-2-GP 
1 2
R9927 
4K7R2J-2-GP 
1 2
R552 
200KR2F-L-GP 1 2
R9761 
4K7R2J-2-GP NOPOP 
1 2
PC1237 
SCD1U50V3KX-GP 
1 2 SR1093 
4K7R2F-GP 
NOPOP 
1 2
SR1123 
4K7R2F-GP 
1 2
R9892 
1K82R2F-1-GP 
NOPOP 1 2
Q28 
2N7002A-7-GP 
G
SD
R9893 
1K82R2F-1-GP 
NOPOP 
1 2
R9591 
10R2F-L-GP 
1 2
Q34 
2N7002A-7-GP 
G
SD
R9777 
47KR2J-2-GP 
1 2
Q32 
2N7002A-7-GP 
G
SD
R9929 
4K7R2J-2-GP 
1 2
S
S
S
G D
D
D
D
U9 
P2003EVG-GP 
1
2
3
4 5
6
7
8
R9494 
10R2F-L-GP 
1 2
PC1235 
SC22U25V6KX-GP-U 
1 2
Q29 
2N7002A-7-GP 
G
SD
R386 0R2J-2-GP 1 2
R119 
4K7R2J-2-GP 
1 2
R380 0R2J-2-GP 1 2
SR1121 
4K7R2F-GP 
1 2
J1 
PCISLT68-14-GP-U1 
GROUND S1 
S0T+/PETP0 S2 
S0T-/PETN0 S3 
GROUND S4 
S0R-/PERN0 S5 
S0R+/PERP0 S6 
GROUND S7 
PCIE_A_REFCLK+ E7 
PCIE_A_REFCLK- E8 
GROUND E9 
PETP0 E10 
PETN0 E11 
GROUND E12 
PERN0 E13 
PERP0 E14 
GROUND E15 
RESERVED1 E16 
PETP3 E17 
PETN3 E18 
GROUND E19 
PERN3 E20 
PERP3 E21 
GROUND E22 
SMCLK E23 
SMDAT E24 
DUALPORTEN# E25 
PCIE_B_REFCLK+ E1 
PCIE_B_REFCLK- E2 
+3D3VAUX E3 
PCIE_B_RST E4 
PCIE_A_RST E5 
RESERVED3 E6 
WAKE# P1 
SPCIERST P2 
RSVD/CLKREQ# P3 
IFDET# P4 
GROUND P5 
GROUND P6 
+5V_PRECHARGE/NC P7 
+5V_A/NC P8 
+5V_B/NC P9 
PRSNT# P10 
ACTIVITY/SPINUP P11 
GROUND P12 
+12V_PRECHARGE P13 
+12V P14 
+12V P15 
GROUND S8 
S1T+/PETP1 S9 
S1T-/PETN1 S10 
GROUND S11 
S1R-/PERN1 S12 
S1R+/PERP1 S13 
GROUND S14 
RESERVED2 S15 
GROUND S16 
PETP1/S2T+ S17 
PETN1/S2T- S18 
GROUND S19 
PERN1/S2R- S20 
PERP1/S2R+ S21 
GROUND S22 
PETP2/S3T+ S23 
PETN2/S3T- S24 
GROUND S25 
PERN2/S3R- S26 
PERP2/S3R+ S27 
GROUND S28 
NP1 NP1 
NP2 NP2 
PTH1 PTH1 
PTH2 PTH2 R567 
300KR2F-GP 1 2
PC1236 
SC22U25V6KX-GP-U 
1 2
R9930 
4K7R2J-2-GP 
1 2
R551 
200KR2F-L-GP 1 2
SR1094 
4K7R2F-GP 
NOPOP 
1 2
R9928 
4K7R2J-2-GP 
1 2
R9785 
1KR2J-1-GP 
1 2
R9492 
4K7R2J-2-GP 
1 2
PC1185 
SC22U25V6KX-GP-U 
1 2
PC1238 
SCD01U50V2KX-1GP 
1 2
R9912 
47KR2J-2-GP 
1 2
C111 
SC1KP50V2KX-1GP 
1 2
R138 
4K7R2J-2-GP 
1 2
C9365 
SC1KP50V2KX-1GP 
1 2
R9449 
330R2F-GP 
1 2
R9913 
47KR2J-2-GP 
1 2
R9239 
2R2010F-GP 
1 2
Q35 
2N7002A-7-GP 
G
SD
D19 
RB551V30-1-GP 
KA
PC1186 
SC22U25V6KX-GP-U 
1 2
R9248 
2R2010F-GP 
1 2
R9786 
47KR2J-2-GP 
1 2
R137 
4K7R2J-2-GP 
1 2
PC1189 
SCD1U25V3KX-GP 
1 2
Q9 
2N7002A-7-GP 
G
SD
C9518 
SCD1U16V2KX-3GP 
1 2
Q8 
2N7002A-7-GP 
G
SD
J100 
PCISLT68-14-GP-U1 
GROUND S1 
S0T+/PETP0 S2 
S0T-/PETN0 S3 
GROUND S4 
S0R-/PERN0 S5 
S0R+/PERP0 S6 
GROUND S7 
PCIE_A_REFCLK+ E7 
PCIE_A_REFCLK- E8 
GROUND E9 
PETP0 E10 
PETN0 E11 
GROUND E12 
PERN0 E13 
PERP0 E14 
GROUND E15 
RESERVED1 E16 
PETP3 E17 
PETN3 E18 
GROUND E19 
PERN3 E20 
PERP3 E21 
GROUND E22 
SMCLK E23 
SMDAT E24 
DUALPORTEN# E25 
PCIE_B_REFCLK+ E1 
PCIE_B_REFCLK- E2 
+3D3VAUX E3 
PCIE_B_RST E4 
PCIE_A_RST E5 
RESERVED3 E6 
WAKE# P1 
SPCIERST P2 
RSVD/CLKREQ# P3 
IFDET# P4 
GROUND P5 
GROUND P6 
+5V_PRECHARGE/NC P7 
+5V_A/NC P8 
+5V_B/NC P9 
PRSNT# P10 
ACTIVITY/SPINUP P11 
GROUND P12 
+12V_PRECHARGE P13 
+12V P14 
+12V P15 
GROUND S8 
S1T+/PETP1 S9 
S1T-/PETN1 S10 
GROUND S11 
S1R-/PERN1 S12 
S1R+/PERP1 S13 
GROUND S14 
RESERVED2 S15 
GROUND S16 
PETP1/S2T+ S17 
PETN1/S2T- S18 
GROUND S19 
PERN1/S2R- S20 
PERP1/S2R+ S21 
GROUND S22 
PETP2/S3T+ S23 
PETN2/S3T- S24 
GROUND S25 
PERN2/S3R- S26 
PERP2/S3R+ S27 
GROUND S28 
NP1 NP1 
NP2 NP2 
PTH1 PTH1 
PTH2 PTH2 
Q30 
2N7002A-7-GP 
G
SD
LED1 
LED-RB-4-GP 
1
3 2
4
C9519 
SCD1U16V2KX-3GP 
1 2
LED100 
LED-RB-4-GP 
1
3 2
4
R9452 
10R2F-L-GP 
1 2
R9495 
4K7R2J-2-GP 
1 2
PC1187 
SCD1U50V3KX-GP 
1 2
R566 
300KR2F-GP 1 2
U198 
SN74LVC1G08DCKR-GP 
B2
A1
GND 3 Y 4
VCC 5
R9590 
10R2F-L-GP 
1 2
C383 
SCD1U25V2KX-2-GP 
12
PC1188 
SCD01U50V2KX-1GP 
1 2
R385 0R2J-2-GP 1 2
Q23 
2N7002A-7-GP 
G
SD
R9788 
0R2J-2-GP 
1 2
SR1124 
4K7R2J-2-GP 
1 2
R9775 
2K2R5F-GP 
1 2
PC1239 
SCD1U25V3KX-GP 
1 2
R9450 
100R2J-2-GP 
1 2
C382 
SCD1U25V2KX-2-GP 
12
R384 0R2J-2-GP 1 2
S
S
S
G D
D
D
D
U10 
P2003EVG-GP 
1
2
3
4 5
6
7
8
U197 
SN74LVC1G08DCKR-GP 
B2
A1
GND 3 Y 4
VCC 5
R9451 
4K7R2J-2-GP 
1 2
R9787 
0R2J-2-GP 
1 2
Q24 
2N7002A-7-GP 
G
SD
D18 
RB551V30-1-GP 
KA
C9353 
SC1KP50V2KX-1GP 
1 2
R9781 
0R2J-2-GP 
1 2
SR1122 
4K7R2J-2-GP 
1 2
SR1092 
4K7R2F-GP 
NOPOP 
1 2
C110 
SC1KP50V2KX-1GP 
1 2
R9499 
4K7R2J-2-GP 
1 2
R118 
4K7R2J-2-GP 
1 2
R111 
330R2F-GP 
1 2
R9784 
2K2R5F-GP 
1 2
SR1091 
4K7R2F-GP 
NOPOP 
1 2
R9782 
0R2J-2-GP 
1 2
R9789 
0R2J-2-GP 
1 2
R9776 
1KR2J-1-GP 
1 2
Q33 
2N7002A-7-GP 
G
SD
R9760 
4K7R2J-2-GP 
NOPOP 
1 2
Q31 
2N7002A-7-GP 
G
SD
R120 
100R2J-2-GP 
1 2



5
5
4
4
3
3
2
2
1
1
D D
C C
B B
A A
SSD2 
SSD3 
Close to 
Connect 
Close to 
Connect 
Close to 
EU2 
Blue 
Red 
ID=-9A 
RDS(on) 
=20m ohm 
P-Channel N-Channel 
Close to 
EU2 
Close to 
EU3 
Blue 
Red 
N-Channel 
Close to 
EU3 
ID=-9A 
RDS(on) 
=20m ohm 
P-Channel 
N-Channel 
N-Channel 
0.01U 
0402 
X7R 
22U 
1206 
X6S 
22U 
1206 
X6S 
0.1U 
0603 
X7R 
0.01U 
0402 
X7R 
22U 
1206 
X6S 
22U 
1206 
X6S 
0.1U 
0603 
X7R 
SSD_ACT_DR2 
SSD2_CLK0_OE_n 
SSD_PRSNT_NET2 
SSD_ACT_DR3 
SSD3_CLK0_OE_n 
SSD_PRSNT_NET3 
SCL_DR2_R 
SDA_DR2_R 
SCL_DR3_R 
SDA_DR3_R 
DUALPORTEN#2 
DUALPORTEN#3 
12V_PRECH_SSD2 
12V_PRECH_SSD3 
SSD_ACT_DR2 
SSD2_PWREN_R SSD2_PWREN 
P12V_MOST2_GATE 
P12V_MOST2_GATE_D 
SSD2_CLK0_OE_R_n 
SSD_PRSNT_NET2 
ATTN_LED_DR2_R 
SSD2_CLK0_OE_MOS_n 
SSD_ACT_DR2_R 
ATTN_LED_DR2_MOS_N 
SSD_ACT_DR2_MOS_N 
DRV_ATTN_2 
SW_SSD2_N 
SW_SSD2_R 
SSD2_CLK0_OE_n 
SSD_PRSNT_NET3 
ATTN_LED_DR3_AND_R 
SSD3_PWREN SSD3_PWREN_R 
P12V_MOST3_GATE_D 
P12V_MOST3_GATE 
SSD3_CLK0_OE_R_n 
ATTN_LED_DR3_R 
SSD3_CLK0_OE_MOS_n 
SSD_ACT_DR3_R 
SSD_ACT_DR3_MOS_N 
ATTN_LED_DR3_MOS_N DRV_ATTN_3 
SSD3_CLK0_OE_n 
SW_SSD3_N 
SW_SSD3_R 
SSD_ACT_DR3 
DRV_ACT_2 
DRV_ACT_3 
ATTN_LED_DR2_AND_R 
ATTN_LED_DR2_AND 
ATTN_LED_DR3_AND 
P3V3 P12V_SSD2 
P3V3 P12V_SSD3 
P3V3 
P12V_SSD2 
P3V3 
P12V_SSD3 
P3V3 
P3V3 
P12V P12V_SSD2 
P3V3 
P3V3 P3V3 
P3V3 
P3V3 
P12V P12V_SSD2 P12V P3V3 
P3V3 
P3V3 
P3V3 
P3V3 
P12V_SSD3 P12V 
P3V3 P3V3 
P3V3 
P3V3 
P12V P12V_SSD3 P12V 
P12V 
P12V 
P3V3 
P3V3 
P3V3 
P3V3 
P3V3 
P3V3 
PE_RX1_DR2_n 16
PE_RX1_DR2_p 16
PE_TX3_DR2_p 16 
PE_TX3_DR2_n 16 
SDA_DR2 20
SCL_DR2 20
PE_RX4_DR2_p 16
PE_RX4_DR2_n 16
PE_RX3_DR2_p 16
PE_RX3_DR2_n 16
PE_CLK100M_dr2_2_p 21 
PE_CLK100M_dr2_2_n 21 
PE_TX2_DR2_n 16 
PE_TX2_DR2_p 16 
SSD2_PERST_N 16 
PE_TX1_DR2_p 16 
PE_TX1_DR2_n 16 
PE_CLK100M_dr2_1_p 21 
PE_CLK100M_dr2_1_n 21 
PE_RX2_DR2_n 16
PE_RX2_DR2_p 16
PE_TX4_DR2_n 16 
PE_TX4_DR2_p 16 
PE_RX1_DR3_n 16
PE_RX1_DR3_p 16
PE_TX3_DR3_p 16 
PE_TX3_DR3_n 16 
SDA_DR3 20
SCL_DR3 20
PE_RX4_DR3_p 16
PE_RX4_DR3_n 16
PE_RX3_DR3_p 16
PE_RX3_DR3_n 16
PE_CLK100M_dr3_2_p 22 
PE_CLK100M_dr3_2_n 22 
PE_TX2_DR3_n 16 
PE_TX2_DR3_p 16 
SSD3_PERST_N 16 
PE_TX1_DR3_p 16 
PE_TX1_DR3_n 16 
PE_CLK100M_dr3_1_p 22 
PE_CLK100M_dr3_1_n 22 
PE_RX2_DR3_n 16
PE_RX2_DR3_p 16
PE_TX4_DR3_n 16 
PE_TX4_DR3_p 16 
ATTN_LED_DR2_N 9,16 
SSD_PRSNT2 21 
ATTN_LED_DR2_N 9,16 
SSD2_PWREN 16 
SSD2_CLK0_OE_R_n 16,21 
SSD_PRSNT3 22 
ATTN_LED_DR3_N 9,16 
ATTN_LED_DR3_N 9,16 
SSD3_CLK0_OE_R_n 16,22 
SSD3_PWREN 16 
Title 
Size Document Number Rev
Date: Sheet 
of 
Lightning_PDPB 
1
SSD CNs 2-3 
A2 
9 28Thursday, March 09, 2017 
Wiwynn 
H/W R&D Dept. II 
8F,90,Sec. 1,Hsin Tai Wu Rd, 
Hsichih, Taipei Hsien 221, Taiwan, R.O.C
Title 
Size Document Number Rev
Date: Sheet 
of 
Lightning_PDPB 
1
SSD CNs 2-3 
A2 
9 28Thursday, March 09, 2017 
Wiwynn 
H/W R&D Dept. II 
8F,90,Sec. 1,Hsin Tai Wu Rd, 
Hsichih, Taipei Hsien 221, Taiwan, R.O.C
Title 
Size Document Number Rev
Date: Sheet 
of 
Lightning_PDPB 
1
SSD CNs 2-3 
A2 
9 28Thursday, March 09, 2017 
Wiwynn 
H/W R&D Dept. II 
8F,90,Sec. 1,Hsin Tai Wu Rd, 
Hsichih, Taipei Hsien 221, Taiwan, R.O.C
SR1125 
4K7R2F-GP 
1 2
PC1228 
SCD01U50V2KX-1GP 
1 2
R9501 
4K7R2J-2-GP 
1 2
U199 
SN74LVC1G08DCKR-GP 
B2
A1
GND 3 Y 4
VCC 5
S
S
S
G D
D
D
D
U11 
P2003EVG-GP 
1
2
3
4 5
6
7
8
R9914 
47KR2J-2-GP 
1 2
J3 
PCISLT68-14-GP-U1 
GROUND S1 
S0T+/PETP0 S2 
S0T-/PETN0 S3 
GROUND S4 
S0R-/PERN0 S5 
S0R+/PERP0 S6 
GROUND S7 
PCIE_A_REFCLK+ E7 
PCIE_A_REFCLK- E8 
GROUND E9 
PETP0 E10 
PETN0 E11 
GROUND E12 
PERN0 E13 
PERP0 E14 
GROUND E15 
RESERVED1 E16 
PETP3 E17 
PETN3 E18 
GROUND E19 
PERN3 E20 
PERP3 E21 
GROUND E22 
SMCLK E23 
SMDAT E24 
DUALPORTEN# E25 
PCIE_B_REFCLK+ E1 
PCIE_B_REFCLK- E2 
+3D3VAUX E3 
PCIE_B_RST E4 
PCIE_A_RST E5 
RESERVED3 E6 
WAKE# P1 
SPCIERST P2 
RSVD/CLKREQ# P3 
IFDET# P4 
GROUND P5 
GROUND P6 
+5V_PRECHARGE/NC P7 
+5V_A/NC P8 
+5V_B/NC P9 
PRSNT# P10 
ACTIVITY/SPINUP P11 
GROUND P12 
+12V_PRECHARGE P13 
+12V P14 
+12V P15 
GROUND S8 
S1T+/PETP1 S9 
S1T-/PETN1 S10 
GROUND S11 
S1R-/PERN1 S12 
S1R+/PERP1 S13 
GROUND S14 
RESERVED2 S15 
GROUND S16 
PETP1/S2T+ S17 
PETN1/S2T- S18 
GROUND S19 
PERN1/S2R- S20 
PERP1/S2R+ S21 
GROUND S22 
PETP2/S3T+ S23 
PETN2/S3T- S24 
GROUND S25 
PERN2/S3R- S26 
PERP2/S3R+ S27 
GROUND S28 
NP1 NP1 
NP2 NP2 
PTH1 PTH1 
PTH2 PTH2 
R9915 
47KR2J-2-GP 
1 2
SR1098 
4K7R2F-GP 
NOPOP 
1 2
C9363 
SC1KP50V2KX-1GP 
1 2
SR1128 
4K7R2J-2-GP 
1 2 R569 
300KR2F-GP 1 2
R9895 
1K82R2F-1-GP 
NOPOP 
1 2
SR1095 
4K7R2F-GP 
NOPOP 
1 2
U200 
SN74LVC1G08DCKR-GP 
B2
A1
GND 3 Y 4
VCC 5
R9799 
1KR2J-1-GP 
1 2
R9593 
10R2F-L-GP 
1 2
Q45 
2N7002A-7-GP 
G
SD
R392 0R2J-2-GP 1 2
Q40 
2N7002A-7-GP 
G
SD
R9261 
2R2010F-GP 
1 2
LED3 
LED-RB-4-GP 
1
3 2
4
R141 
4K7R2J-2-GP 
1 2
R553 
200KR2F-L-GP 
1 2
R9592 
10R2F-L-GP 
1 2
R9488 
4K7R2J-2-GP 
1 2
R9794 
47KR2J-2-GP 
1 2
SR1096 
4K7R2F-GP 
NOPOP 
1 2
R9442 
330R2F-GP 
1 2
R9503 
4K7R2J-2-GP 
1 2
D21 
RB551V30-1-GP 
KA
R9594 
10R2F-L-GP 
1 2
Q11 
2N7002A-7-GP 
G
SD
R9762 
4K7R2J-2-GP 
NOPOP 
1 2
PC1192 
SCD1U50V3KX-GP 
1 2
J2 
PCISLT68-14-GP-U1 
GROUND S1 
S0T+/PETP0 S2 
S0T-/PETN0 S3 
GROUND S4 
S0R-/PERN0 S5 
S0R+/PERP0 S6 
GROUND S7 
PCIE_A_REFCLK+ E7 
PCIE_A_REFCLK- E8 
GROUND E9 
PETP0 E10 
PETN0 E11 
GROUND E12 
PERN0 E13 
PERP0 E14 
GROUND E15 
RESERVED1 E16 
PETP3 E17 
PETN3 E18 
GROUND E19 
PERN3 E20 
PERP3 E21 
GROUND E22 
SMCLK E23 
SMDAT E24 
DUALPORTEN# E25 
PCIE_B_REFCLK+ E1 
PCIE_B_REFCLK- E2 
+3D3VAUX E3 
PCIE_B_RST E4 
PCIE_A_RST E5 
RESERVED3 E6 
WAKE# P1 
SPCIERST P2 
RSVD/CLKREQ# P3 
IFDET# P4 
GROUND P5 
GROUND P6 
+5V_PRECHARGE/NC P7 
+5V_A/NC P8 
+5V_B/NC P9 
PRSNT# P10 
ACTIVITY/SPINUP P11 
GROUND P12 
+12V_PRECHARGE P13 
+12V P14 
+12V P15 
GROUND S8 
S1T+/PETP1 S9 
S1T-/PETN1 S10 
GROUND S11 
S1R-/PERN1 S12 
S1R+/PERP1 S13 
GROUND S14 
RESERVED2 S15 
GROUND S16 
PETP1/S2T+ S17 
PETN1/S2T- S18 
GROUND S19 
PERN1/S2R- S20 
PERP1/S2R+ S21 
GROUND S22 
PETP2/S3T+ S23 
PETN2/S3T- S24 
GROUND S25 
PERN2/S3R- S26 
PERP2/S3R+ S27 
GROUND S28 
NP1 NP1 
NP2 NP2 
PTH1 PTH1 
PTH2 PTH2 
C940 
SC1KP50V2KX-1GP 
1 2
R9400 
330R2F-GP 
1 2
R9800 
47KR2J-2-GP 
1 2
R9894 
1K82R2F-1-GP 
NOPOP 
1 2
R9443 
100R2J-2-GP 
1 2
C384 
SCD1U25V2KX-2-GP 
12
PC1190 
SC22U25V6KX-GP-U 
1 2
R9801 
0R2J-2-GP 
1 2 R393 0R2J-2-GP 1 2
R9444 
4K7R2J-2-GP 
1 2
C939 
SC1KP50V2KX-1GP 
1 2
R568 
300KR2F-GP 1 2
LED2 
LED-RB-4-GP 
1
3 2
4
R9934 
4K7R2J-2-GP 
1 2
PC1191 
SC22U25V6KX-GP-U 
1 2
R9798 
2K2R5F-GP 
1 2
R9802 
0R2J-2-GP 
1 2
C9351 
SC1KP50V2KX-1GP 
1 2
Q43 
2N7002A-7-GP 
G
SD
R9402 
4K7R2J-2-GP 
1 2
PC1193 
SCD01U50V2KX-1GP 
1 2
S
S
S
G D
D
D
D
U12 
P2003EVG-GP 
1
2
3
4 5
6
7
8
R9931 
4K7R2J-2-GP 
1 2
SR1126 
4K7R2J-2-GP 
1 2
R9401 
100R2J-2-GP 
1 2
SR1127 
4K7R2F-GP 
1 2
R9795 
0R2J-2-GP 
1 2
R139 
4K7R2J-2-GP 
1 2
R391 0R2J-2-GP 1 2
Q38 
2N7002A-7-GP 
G
SD
R9490 
4K7R2J-2-GP 
1 2
Q41 
2N7002A-7-GP 
G
SD
Q36 
2N7002A-7-GP 
G
SD
D20 
RB551V30-1-GP 
KA
R9792 
2K2R5F-GP 
1 2
PC1227 
SCD1U50V3KX-GP 
1 2
PC1194 
SCD1U25V3KX-GP 
1 2
Q10 
2N7002A-7-GP 
G
SD
R9243 
2R2010F-GP 
1 2
Q39 
2N7002A-7-GP 
G
SD R9796 
0R2J-2-GP 
1 2
R554 
200KR2F-L-GP 1 2
R9595 
10R2F-L-GP 
1 2
R9763 
4K7R2J-2-GP 
NOPOP 
1 2
R9803 
0R2J-2-GP 
1 2
Q37 
2N7002A-7-GP 
G
SD
R9933 
4K7R2J-2-GP 
1 2
PC1225 
SC22U25V6KX-GP-U 
1 2
Q44 
2N7002A-7-GP 
G
SD
C9521 
SCD1U16V2KX-3GP 
1 2
SR1097 
4K7R2F-GP 
NOPOP 
1 2
R9793 
1KR2J-1-GP 
1 2
C9520 
SCD1U16V2KX-3GP 
1 2
PC1226 
SC22U25V6KX-GP-U 
1 2
R9797 
0R2J-2-GP 
1 2
PC1229 
SCD1U25V3KX-GP 
1 2
R9932 
4K7R2J-2-GP 
1 2
C385 
SCD1U25V2KX-2-GP 
12
Q42 
2N7002A-7-GP 
G
SD
R394 0R2J-2-GP 1 2



5
5
4
4
3
3
2
2
1
1
D D
C C
B B
A A
SSD4 
SSD5 
Close to 
Connect 
Close to 
Connect 
DVT 
20160506 
Close to 
EU4 
Close to 
EU4 
N-Channel 
Blue 
Red 
ID=-9A 
RDS(on) 
=20m ohm 
P-Channel 
Close to 
EU1 
ID=-9A 
RDS(on) 
=20m ohm 
P-Channel 
N-Channel 
Blue 
Red 
Close to 
EU1 
N-Channel 
N-Channel 
0.01U 
0402 
X7R 
22U 
1206 
X6S 
22U 
1206 
X6S 
0.1U 
0603 
X7R 
0.01U 
0402 
X7R 
22U 
1206 
X6S 
22U 
1206 
X6S 
0.1U 
0603 
X7R 
SSD_ACT_DR4 
SSD4_CLK0_OE_n 
SSD_PRSNT_NET4 
SSD_ACT_DR5 
SSD5_CLK0_OE_n 
SSD_PRSNT_NET5 
SCL_DR4_R 
SDA_DR4_R 
SCL_DR5_R 
SDA_DR5_R 
DUALPORTEN#4 
DUALPORTEN#5 
12V_PRECH_SSD4 
12V_PRECH_SSD5 
SSD_PRSNT_NET4 
SSD_ACT_DR4 
SSD4_PWREN SSD4_PWREN_R 
P12V_MOST4_GATE_D 
P12V_MOST4_GATE 
SSD4_CLK0_OE_R_n 
ATTN_LED_DR4_R 
SSD4_CLK0_OE_MOS_n 
SSD_ACT_DR4_R 
SSD_ACT_DR4_MOS_N 
ATTN_LED_DR4_MOS_N DRV_ATTN_4 
SSD4_CLK0_OE_n 
SW_SSD4_R 
SW_SSD4_N 
SW_SSD5_R 
SW_SSD5_N 
SSD_PRSNT_NET5 SSD5_CLK0_OE_n 
ATTN_LED_DR5_AND_R 
SSD_ACT_DR5 
SSD5_PWREN SSD5_PWREN_R 
P12V_MOST5_GATE_D 
P12V_MOST5_GATE 
SSD5_CLK0_OE_R_n 
ATTN_LED_DR5_R 
SSD5_CLK0_OE_MOS_n 
SSD_ACT_DR5_R 
SSD_ACT_DR5_MOS_N 
ATTN_LED_DR5_MOS_N DRV_ATTN_5 
DRV_ACT_4 
DRV_ACT_5 
ATTN_LED_DR4_AND_R 
ATTN_LED_DR4_AND 
ATTN_LED_DR5_AND 
P3V3 
P12V_SSD4 
P3V3 P12V_SSD5 
P3V3 
P12V_SSD4 
P3V3 
P12V_SSD5 
P3V3 
P3V3 
P3V3 
P3V3 
P12V_SSD4 P12V 
P3V3 P3V3 
P3V3 
P3V3 
P3V3 P12V P12V_SSD4 P12V 
P3V3 
P12V P12V_SSD5 P12V 
P3V3 
P3V3 
P3V3 
P12V_SSD5 P12V 
P3V3 P3V3 
P3V3 
P12V 
P12V 
P3V3 
P3V3 
P3V3 
P3V3 
P3V3 
P3V3 
PE_RX1_DR4_n 17
PE_RX1_DR4_p 17
PE_TX3_DR4_p 16 
PE_TX3_DR4_n 16 
SDA_DR4 20
SCL_DR4 20
PE_RX4_DR4_p 16
PE_RX4_DR4_n 16
PE_RX3_DR4_p 16
PE_RX3_DR4_n 16
PE_CLK100M_dr4_2_p 22 
PE_CLK100M_dr4_2_n 22 
PE_TX2_DR4_n 17 
PE_TX2_DR4_p 17 
SSD4_PERST_N 17 
PE_TX1_DR4_p 17 
PE_TX1_DR4_n 17 
PE_CLK100M_dr4_1_p 22 
PE_CLK100M_dr4_1_n 22 
PE_RX2_DR4_n 17
PE_RX2_DR4_p 17
PE_TX4_DR4_n 16 
PE_TX4_DR4_p 16 
PE_RX1_DR5_p 16
PE_RX1_DR5_n 16
PE_TX3_DR5_n 16 
PE_TX3_DR5_p 16 
SDA_DR5 20
SCL_DR5 20
PE_RX4_DR5_n 16
PE_RX4_DR5_p 16
PE_RX3_DR5_n 16
PE_RX3_DR5_p 16
PE_CLK100M_dr5_2_p 21 
PE_CLK100M_dr5_2_n 21 
PE_TX2_DR5_p 16 
PE_TX2_DR5_n 16 
SSD5_PERST_N 16 
PE_TX1_DR5_n 16 
PE_TX1_DR5_p 16 
PE_CLK100M_dr5_1_p 21 
PE_CLK100M_dr5_1_n 21 
PE_RX2_DR5_p 16
PE_RX2_DR5_n 16
PE_TX4_DR5_p 16 
PE_TX4_DR5_n 16 
SSD_PRSNT4 22 
ATTN_LED_DR4_N 10,17 
ATTN_LED_DR4_N 10,17 
SSD4_CLK0_OE_R_n 17,22 
SSD4_PWREN 17 
SSD5_PWREN 16 
SSD_PRSNT5 21 SSD5_CLK0_OE_R_n 16,21 
ATTN_LED_DR5_N 10,16 
ATTN_LED_DR5_N 10,16 
Title 
Size Document Number Rev
Date: Sheet 
of 
Lightning_PDPB 1
SSD CNs 4-5 
A2 
10 28Thursday, March 09, 2017 
Wiwynn 
H/W R&D Dept. II 
8F,90,Sec. 1,Hsin Tai Wu Rd, 
Hsichih, Taipei Hsien 221, Taiwan, R.O.C
Title 
Size Document Number Rev
Date: Sheet 
of 
Lightning_PDPB 1
SSD CNs 4-5 
A2 
10 28Thursday, March 09, 2017 
Wiwynn 
H/W R&D Dept. II 
8F,90,Sec. 1,Hsin Tai Wu Rd, 
Hsichih, Taipei Hsien 221, Taiwan, R.O.C
Title 
Size Document Number Rev
Date: Sheet 
of 
Lightning_PDPB 1
SSD CNs 4-5 
A2 
10 28Thursday, March 09, 2017 
Wiwynn 
H/W R&D Dept. II 
8F,90,Sec. 1,Hsin Tai Wu Rd, 
Hsichih, Taipei Hsien 221, Taiwan, R.O.C
R9599 
10R2F-L-GP 
1 2
R9407 
330R2F-GP 
1 2
Q53 
2N7002A-7-GP 
G
SD
SR1131 
4K7R2F-GP 
1 2
R9917 
47KR2J-2-GP 
1 2
R570 
300KR2F-GP 1 2
R9765 
4K7R2J-2-GP 
NOPOP 
1 2
C387 
SCD1U25V2KX-2-GP 
12
PC1209 
SCD1U25V3KX-GP 
1 2
R396 0R2J-2-GP 1 2
R9598 
10R2F-L-GP 
1 2
SR1101 
4K7R2F-GP 
NOPOP 
1 2
SR1132 
4K7R2J-2-GP 
1 2
Q50 
2N7002A-7-GP 
G
SD
R9764 
4K7R2J-2-GP 
NOPOP 
1 2
LED4 
LED-RB-4-GP 
1
3 2
4
Q51 
2N7002A-7-GP 
G
SD
R142 
4K7R2J-2-GP 
1 2
R9816 
0R2J-2-GP 
1 2
U202 
SN74LVC1G08DCKR-GP 
B2
A1
GND 3 Y 4
VCC 5
R9935 
4K7R2J-2-GP 
1 2
R9806 
47KR2J-2-GP 
1 2
S
S
S
G D
D
D
D
U14 
P2003EVG-GP 
1
2
3
4 5
6
7
8
R9408 
100R2J-2-GP 
1 2
C9367 
SC1KP50V2KX-1GP 
1 2
R9938 
4K7R2J-2-GP 
1 2
D22 
RB551V30-1-GP 
KA
Q12 
2N7002A-7-GP 
G
SD
R9596 
10R2F-L-GP 
1 2
R9807 
0R2J-2-GP 
1 2
SR1102 
4K7R2F-GP 
NOPOP 
1 2
R9416 
4K7R2J-2-GP 
1 2
R9812 
2K2R5F-GP 
1 2
C9343 
SC1KP50V2KX-1GP 
1 2
R397 0R2J-2-GP 1 2
R9597 
10R2F-L-GP 
1 2
Q52 
2N7002A-7-GP 
G
SD
PC1207 
SCD1U50V3KX-GP 
1 2
Q48 
2N7002A-7-GP 
G
SD
SR1129 
4K7R2F-GP 
1 2
Q54 
2N7002A-7-GP 
G
SD
R9817 
0R2J-2-GP 
1 2
R9804 
2K2R5F-GP 
1 2
R556 
200KR2F-L-GP 1 2
PC1202 
SCD1U50V3KX-GP 
1 2
SR1130 
4K7R2J-2-GP 
1 2
PC1204 
SCD1U25V3KX-GP 
1 2
R9896 
1K82R2F-1-GP 
NOPOP 
1 2
R9897 
1K82R2F-1-GP 
NOPOP 
1 2
R9916 
47KR2J-2-GP 
1 2
PC1205 
SC22U25V6KX-GP-U 
1 2
C386 
SCD1U25V2KX-2-GP 
12
PC1200 
SC22U25V6KX-GP-U 
1 2
C9341 
SC1KP50V2KX-1GP 
1 2
R9937 
4K7R2J-2-GP 
1 2
Q46 
2N7002A-7-GP 
G
SD
S
S
S
G D
D
D
D
U13 
P2003EVG-GP 
1
2
3
4 5
6
7
8
R9813 
1KR2J-1-GP 
1 2
PC1206 
SC22U25V6KX-GP-U 
1 2
R9808 
0R2J-2-GP 
1 2
SR1099 
4K7R2F-GP 
NOPOP 
1 2
R395 0R2J-2-GP 1 2
PC1201 
SC22U25V6KX-GP-U 
1 2
R9496 
4K7R2J-2-GP 
1 2
J5 
PCISLT68-14-GP-U1 
GROUND S1 
S0T+/PETP0 S2 
S0T-/PETN0 S3 
GROUND S4 
S0R-/PERN0 S5 
S0R+/PERP0 S6 
GROUND S7 
PCIE_A_REFCLK+ E7 
PCIE_A_REFCLK- E8 
GROUND E9 
PETP0 E10 
PETN0 E11 
GROUND E12 
PERN0 E13 
PERP0 E14 
GROUND E15 
RESERVED1 E16 
PETP3 E17 
PETN3 E18 
GROUND E19 
PERN3 E20 
PERP3 E21 
GROUND E22 
SMCLK E23 
SMDAT E24 
DUALPORTEN# E25 
PCIE_B_REFCLK+ E1 
PCIE_B_REFCLK- E2 
+3D3VAUX E3 
PCIE_B_RST E4 
PCIE_A_RST E5 
RESERVED3 E6 
WAKE# P1 
SPCIERST P2 
RSVD/CLKREQ# P3 
IFDET# P4 
GROUND P5 
GROUND P6 
+5V_PRECHARGE/NC P7 
+5V_A/NC P8 
+5V_B/NC P9 
PRSNT# P10 
ACTIVITY/SPINUP P11 
GROUND P12 
+12V_PRECHARGE P13 
+12V P14 
+12V P15 
GROUND S8 
S1T+/PETP1 S9 
S1T-/PETN1 S10 
GROUND S11 
S1R-/PERN1 S12 
S1R+/PERP1 S13 
GROUND S14 
RESERVED2 S15 
GROUND S16 
PETP1/S2T+ S17 
PETN1/S2T- S18 
GROUND S19 
PERN1/S2R- S20 
PERP1/S2R+ S21 
GROUND S22 
PETP2/S3T+ S23 
PETN2/S3T- S24 
GROUND S25 
PERN2/S3R- S26 
PERP2/S3R+ S27 
GROUND S28 
NP1 NP1 
NP2 NP2 
PTH1 PTH1 
PTH2 PTH2 
R9414 
330R2F-GP 
1 2
C9366 
SC1KP50V2KX-1GP 
1 2
PC1208 
SCD01U50V2KX-1GP 
1 2
R9500 
4K7R2J-2-GP 
1 2
PC1203 
SCD01U50V2KX-1GP 
1 2
R571 
300KR2F-GP 1 2
R9809 
0R2J-2-GP 
1 2
R398 0R2J-2-GP 1 2
LED5 
LED-RB-4-GP 
1
3 2
4
Q55 
2N7002A-7-GP 
G
SD
U201 
SN74LVC1G08DCKR-GP 
B2
A1
GND 3 Y 4
VCC 5
Q47 
2N7002A-7-GP 
G
SD SR1100 
4K7R2F-GP 
NOPOP 
1 2
R143 
4K7R2J-2-GP 
1 2
Q49 
2N7002A-7-GP 
G
SD
R9409 
4K7R2J-2-GP 
1 2
R9245 
2R2010F-GP 
1 2
R9508 
4K7R2J-2-GP 
1 2
R555 
200KR2F-L-GP 1 2
R9244 
2R2010F-GP 
1 2
R9814 
47KR2J-2-GP 
1 2
C9522 
SCD1U16V2KX-3GP 
1 2
R9506 
4K7R2J-2-GP 
1 2
R9415 
100R2J-2-GP 
1 2
Q13 
2N7002A-7-GP 
G
SD
C9523 
SCD1U16V2KX-3GP 
1 2
R9805 
1KR2J-1-GP 
1 2
R9815 
0R2J-2-GP 
1 2
D23 
RB551V30-1-GP 
KA
J4 
PCISLT68-14-GP-U1 
GROUND S1 
S0T+/PETP0 S2 
S0T-/PETN0 S3 
GROUND S4 
S0R-/PERN0 S5 
S0R+/PERP0 S6 
GROUND S7 
PCIE_A_REFCLK+ E7 
PCIE_A_REFCLK- E8 
GROUND E9 
PETP0 E10 
PETN0 E11 
GROUND E12 
PERN0 E13 
PERP0 E14 
GROUND E15 
RESERVED1 E16 
PETP3 E17 
PETN3 E18 
GROUND E19 
PERN3 E20 
PERP3 E21 
GROUND E22 
SMCLK E23 
SMDAT E24 
DUALPORTEN# E25 
PCIE_B_REFCLK+ E1 
PCIE_B_REFCLK- E2 
+3D3VAUX E3 
PCIE_B_RST E4 
PCIE_A_RST E5 
RESERVED3 E6 
WAKE# P1 
SPCIERST P2 
RSVD/CLKREQ# P3 
IFDET# P4 
GROUND P5 
GROUND P6 
+5V_PRECHARGE/NC P7 
+5V_A/NC P8 
+5V_B/NC P9 
PRSNT# P10 
ACTIVITY/SPINUP P11 
GROUND P12 
+12V_PRECHARGE P13 
+12V P14 
+12V P15 
GROUND S8 
S1T+/PETP1 S9 
S1T-/PETN1 S10 
GROUND S11 
S1R-/PERN1 S12 
S1R+/PERP1 S13 
GROUND S14 
RESERVED2 S15 
GROUND S16 
PETP1/S2T+ S17 
PETN1/S2T- S18 
GROUND S19 
PERN1/S2R- S20 
PERP1/S2R+ S21 
GROUND S22 
PETP2/S3T+ S23 
PETN2/S3T- S24 
GROUND S25 
PERN2/S3R- S26 
PERP2/S3R+ S27 
GROUND S28 
NP1 NP1 
NP2 NP2 
PTH1 PTH1 
PTH2 PTH2 
R9936 
4K7R2J-2-GP 
1 2



5
5
4
4
3
3
2
2
1
1
D D
C C
B B
A A
SSD6 
SSD7 
Close to 
Connect 
Close to 
Connect 
Close to 
EU2 
N-Channel 
Blue 
Red 
Close to 
EU2 
ID=-9A 
RDS(on) 
=20m ohm 
P-Channel 
ID=-9A 
RDS(on) 
=20m ohm 
P-Channel 
Close to 
EU2 
N-Channel 
Close to 
EU2 
Blue 
Red 
N-Channel 
N-Channel 
0.01U 
0402 
X7R 
22U 
1206 
X6S 
22U 
1206 
X6S 
0.1U 
0603 
X7R 
0.01U 
0402 
X7R 
22U 
1206 
X6S 
22U 
1206 
X6S 
0.1U 
0603 
X7R 
SSD_ACT_DR6 
SSD6_CLK0_OE_n 
SSD_PRSNT_NET6 
SSD_ACT_DR7 
SSD7_CLK0_OE_n 
SSD_PRSNT_NET7 
SCL_DR6_R 
SDA_DR6_R 
SCL_DR7_R 
SDA_DR7_R 
DUALPORTEN#6 
DUALPORTEN#7 
12V_PRECH_SSD6 
12V_PRECH_SSD7 
SSD_PRSNT_NET6 SSD6_CLK0_OE_n 
ATTN_LED_DR6_AND 
ATTN_LED_DR6_AND_R 
SSD_ACT_DR6 
SSD6_PWREN SSD6_PWREN_R 
P12V_MOST6_GATE_D 
P12V_MOST6_GATE 
SSD6_CLK0_OE_R_n 
ATTN_LED_DR6_R 
SSD6_CLK0_OE_MOS_n 
SSD_ACT_DR6_R 
SSD_ACT_DR6_MOS_N 
ATTN_LED_DR6_MOS_N DRV_ATTN_6 
SW_SSD6_N 
SW_SSD6_R 
SW_SSD7_N 
SW_SSD7_R 
SSD7_CLK0_OE_n SSD_PRSNT_NET7 
ATTN_LED_DR7_AND 
ATTN_LED_DR7_AND_R 
SSD_ACT_DR7 
SSD7_PWREN SSD7_PWREN_R 
P12V_MOST7_GATE_D 
P12V_MOST7_GATE 
SSD7_CLK0_OE_R_n 
ATTN_LED_DR7_R 
SSD7_CLK0_OE_MOS_n 
SSD_ACT_DR7_R 
SSD_ACT_DR7_MOS_N 
ATTN_LED_DR7_MOS_N DRV_ATTN_7 
DRV_ACT_6 
DRV_ACT_7 
P3V3 
P12V_SSD6 
P3V3 
P12V_SSD7 
P3V3 
P12V_SSD6 
P3V3 
P12V_SSD7 
P3V3 
P3V3 
P3V3 
P3V3 
P3V3 
P3V3 
P12V_SSD6 P12V 
P3V3 P3V3 
P3V3 
P12V P12V_SSD6 P12V 
P3V3 
P12V P12V_SSD7 
P12V 
P3V3 
P3V3 P3V3 
P12V_SSD7 P12V 
P3V3 P3V3 
P3V3 
P12V 
P12V 
P3V3 
P3V3 
P3V3 
P3V3 
P3V3 
P3V3 
PE_RX1_DR6_n 16
PE_RX1_DR6_p 16
PE_TX3_DR6_p 16 
PE_TX3_DR6_n 16 
SDA_DR6 20
SCL_DR6 20
PE_RX4_DR6_p 16
PE_RX4_DR6_n 16
PE_RX3_DR6_p 16
PE_RX3_DR6_n 16
PE_CLK100M_dr6_2_p 21 
PE_CLK100M_dr6_2_n 21 
PE_TX2_DR6_n 16 
PE_TX2_DR6_p 16 
SSD6_PERST_N 16 
PE_TX1_DR6_p 16 
PE_TX1_DR6_n 16 
PE_CLK100M_dr6_1_p 21 
PE_CLK100M_dr6_1_n 21 
PE_RX2_DR6_n 16
PE_RX2_DR6_p 16
PE_TX4_DR6_n 16 
PE_TX4_DR6_p 16 
PE_RX1_DR7_n 16
PE_RX1_DR7_p 16
PE_TX3_DR7_p 16 
PE_TX3_DR7_n 16 
SDA_DR7 20
SCL_DR7 20
PE_RX4_DR7_p 16
PE_RX4_DR7_n 16
PE_RX3_DR7_p 16
PE_RX3_DR7_n 16
PE_CLK100M_dr7_2_p 22 
PE_CLK100M_dr7_2_n 22 
PE_TX2_DR7_n 16 
PE_TX2_DR7_p 16 
SSD7_PERST_N 16 
PE_TX1_DR7_p 16 
PE_TX1_DR7_n 16 
PE_CLK100M_dr7_1_p 22 
PE_CLK100M_dr7_1_n 22 
PE_RX2_DR7_n 16
PE_RX2_DR7_p 16
PE_TX4_DR7_n 16 
PE_TX4_DR7_p 16 
SSD_PRSNT6 21 SSD6_CLK0_OE_R_n 16,21 
ATTN_LED_DR6_N 11,16 
ATTN_LED_DR6_N 11,16 
SSD6_PWREN 16 
SSD7_PWREN 16 
SSD7_CLK0_OE_R_n 16,22 SSD_PRSNT7 22 
ATTN_LED_DR7_N 11,16 
ATTN_LED_DR7_N 11,16 
Title 
Size Document Number Rev
Date: Sheet 
of 
Lightning_PDPB 1
SSD CNs 6-7 
A2 
11 28Thursday, March 09, 2017 
Wiwynn 
H/W R&D Dept. II 
8F,90,Sec. 1,Hsin Tai Wu Rd, 
Hsichih, Taipei Hsien 221, Taiwan, R.O.C
Title 
Size Document Number Rev
Date: Sheet 
of 
Lightning_PDPB 1
SSD CNs 6-7 
A2 
11 28Thursday, March 09, 2017 
Wiwynn 
H/W R&D Dept. II 
8F,90,Sec. 1,Hsin Tai Wu Rd, 
Hsichih, Taipei Hsien 221, Taiwan, R.O.C
Title 
Size Document Number Rev
Date: Sheet 
of 
Lightning_PDPB 1
SSD CNs 6-7 
A2 
11 28Thursday, March 09, 2017 
Wiwynn 
H/W R&D Dept. II 
8F,90,Sec. 1,Hsin Tai Wu Rd, 
Hsichih, Taipei Hsien 221, Taiwan, R.O.C
LED7 
LED-RB-4-GP 
1
3 2
4
R9939 
4K7R2J-2-GP 
1 2
R9504 
4K7R2J-2-GP 
1 2
SR1136 
4K7R2J-2-GP 
1 2
U204 
SN74LVC1G08DCKR-GP 
B2
A1
GND 3 Y 4
VCC 5
R144 
4K7R2J-2-GP 
1 2
PC1246 
SC22U25V6KX-GP-U 
1 2
R9600 
10R2F-L-GP 
1 2
Q65 
2N7002A-7-GP 
G
SD
R9823 
0R2J-2-GP 
1 2
SR1104 
4K7R2F-GP 
NOPOP 
1 2
R145 
4K7R2J-2-GP 
1 2
R9826 
2K2R5F-GP 
1 2
R399 0R2J-2-GP 1 2
PC1248 
SCD01U50V2KX-1GP 
1 2
Q59 
2N7002A-7-GP 
G
SD
Q14 
2N7002A-7-GP 
G
SD
R9464 
100R2J-2-GP 
1 2
R9828 
47KR2J-2-GP 
1 2
R401 0R2J-2-GP 1 2
D24 
RB551V30-1-GP 
KA
R573 
300KR2F-GP 1 2
R9516 
4K7R2J-2-GP 
1 2
C388 
SCD1U25V2KX-2-GP 
12
R9829 
0R2J-2-GP 
1 2
R9601 
10R2F-L-GP 
1 2
R9819 
1KR2J-1-GP 
1 2
R9818 
2K2R5F-GP 
1 2
R9470 
330R2F-GP 
1 2
Q61 
2N7002A-7-GP 
G
SD
Q63 
2N7002A-7-GP 
G
SD
Q15 
2N7002A-7-GP 
G
SD
R9250 
2R2010F-GP 
1 2
C9359 
SC1KP50V2KX-1GP 
1 2
R9899 
1K82R2F-1-GP 
NOPOP 
1 2
SR1135 
4K7R2F-GP 
1 2
R9767 
4K7R2J-2-GP NOPOP 
1 2
Q62 
2N7002A-7-GP 
G
SD
C9357 
SC1KP50V2KX-1GP 
1 2
LED6 
LED-RB-4-GP 
1
3 2
4
D25 
RB551V30-1-GP 
KA
Q60 
2N7002A-7-GP 
G
SD
S
S
S
G D
D
D
D
U15 
P2003EVG-GP 
1
2
3
4 5
6
7
8
C389 
SCD1U25V2KX-2-GP 
12
C9368 
SC1KP50V2KX-1GP 
1 2
R9830 
0R2J-2-GP 
1 2
R9942 
4K7R2J-2-GP 
1 2
R9502 
4K7R2J-2-GP 
1 2
R9471 
100R2J-2-GP 
1 2
R9820 
47KR2J-2-GP 
1 2
J7 
PCISLT68-14-GP-U1 
GROUND S1 
S0T+/PETP0 S2 
S0T-/PETN0 S3 
GROUND S4 
S0R-/PERN0 S5 
S0R+/PERP0 S6 
GROUND S7 
PCIE_A_REFCLK+ E7 
PCIE_A_REFCLK- E8 
GROUND E9 
PETP0 E10 
PETN0 E11 
GROUND E12 
PERN0 E13 
PERP0 E14 
GROUND E15 
RESERVED1 E16 
PETP3 E17 
PETN3 E18 
GROUND E19 
PERN3 E20 
PERP3 E21 
GROUND E22 
SMCLK E23 
SMDAT E24 
DUALPORTEN# E25 
PCIE_B_REFCLK+ E1 
PCIE_B_REFCLK- E2 
+3D3VAUX E3 
PCIE_B_RST E4 
PCIE_A_RST E5 
RESERVED3 E6 
WAKE# P1 
SPCIERST P2 
RSVD/CLKREQ# P3 
IFDET# P4 
GROUND P5 
GROUND P6 
+5V_PRECHARGE/NC P7 
+5V_A/NC P8 
+5V_B/NC P9 
PRSNT# P10 
ACTIVITY/SPINUP P11 
GROUND P12 
+12V_PRECHARGE P13 
+12V P14 
+12V P15 
GROUND S8 
S1T+/PETP1 S9 
S1T-/PETN1 S10 
GROUND S11 
S1R-/PERN1 S12 
S1R+/PERP1 S13 
GROUND S14 
RESERVED2 S15 
GROUND S16 
PETP1/S2T+ S17 
PETN1/S2T- S18 
GROUND S19 
PERN1/S2R- S20 
PERP1/S2R+ S21 
GROUND S22 
PETP2/S3T+ S23 
PETN2/S3T- S24 
GROUND S25 
PERN2/S3R- S26 
PERP2/S3R+ S27 
GROUND S28 
NP1 NP1 
NP2 NP2 
PTH1 PTH1 
PTH2 PTH2 
R9821 
0R2J-2-GP 
1 2
PC1244 
SCD1U25V3KX-GP 
1 2
R9898 
1K82R2F-1-GP 
NOPOP 
1 2
PC1242 
SCD1U50V3KX-GP 
1 2
R9918 
47KR2J-2-GP 
1 2
R9603 
10R2F-L-GP 
1 2
SR1134 
4K7R2J-2-GP 
1 2
R9919 
47KR2J-2-GP 
1 2
R400 0R2J-2-GP 1 2
U203 
SN74LVC1G08DCKR-GP 
B2
A1
GND 3 Y 4
VCC 5
R9766 
4K7R2J-2-GP NOPOP 
1 2
PC1240 
SC22U25V6KX-GP-U 
1 2
Q58 
2N7002A-7-GP 
G
SD
R402 0R2J-2-GP 1 2
S
S
S
G D
D
D
D
U16 
P2003EVG-GP 
1
2
3
4 5
6
7
8
R9940 
4K7R2J-2-GP 
1 2
R9831 
0R2J-2-GP 
1 2
PC1249 
SCD1U25V3KX-GP 
1 2
SR1133 
4K7R2F-GP 
1 2
SR1105 
4K7R2F-GP 
NOPOP 
1 2
PC1241 
SC22U25V6KX-GP-U 
1 2
Q64 
2N7002A-7-GP 
G
SD
R557 
200KR2F-L-GP 1 2
R9827 
1KR2J-1-GP 
1 2
R9465 
4K7R2J-2-GP 
1 2
PC1243 
SCD01U50V2KX-1GP 
1 2
R9941 
4K7R2J-2-GP 
1 2
C9525 
SCD1U16V2KX-3GP 
1 2
Q57 
2N7002A-7-GP 
G
SD
C9369 
SC1KP50V2KX-1GP 
1 2
R9618 
4K7R2J-2-GP 
1 2
J6 
PCISLT68-14-GP-U1 
GROUND S1 
S0T+/PETP0 S2 
S0T-/PETN0 S3 
GROUND S4 
S0R-/PERN0 S5 
S0R+/PERP0 S6 
GROUND S7 
PCIE_A_REFCLK+ E7 
PCIE_A_REFCLK- E8 
GROUND E9 
PETP0 E10 
PETN0 E11 
GROUND E12 
PERN0 E13 
PERP0 E14 
GROUND E15 
RESERVED1 E16 
PETP3 E17 
PETN3 E18 
GROUND E19 
PERN3 E20 
PERP3 E21 
GROUND E22 
SMCLK E23 
SMDAT E24 
DUALPORTEN# E25 
PCIE_B_REFCLK+ E1 
PCIE_B_REFCLK- E2 
+3D3VAUX E3 
PCIE_B_RST E4 
PCIE_A_RST E5 
RESERVED3 E6 
WAKE# P1 
SPCIERST P2 
RSVD/CLKREQ# P3 
IFDET# P4 
GROUND P5 
GROUND P6 
+5V_PRECHARGE/NC P7 
+5V_A/NC P8 
+5V_B/NC P9 
PRSNT# P10 
ACTIVITY/SPINUP P11 
GROUND P12 
+12V_PRECHARGE P13 
+12V P14 
+12V P15 
GROUND S8 
S1T+/PETP1 S9 
S1T-/PETN1 S10 
GROUND S11 
S1R-/PERN1 S12 
S1R+/PERP1 S13 
GROUND S14 
RESERVED2 S15 
GROUND S16 
PETP1/S2T+ S17 
PETN1/S2T- S18 
GROUND S19 
PERN1/S2R- S20 
PERP1/S2R+ S21 
GROUND S22 
PETP2/S3T+ S23 
PETN2/S3T- S24 
GROUND S25 
PERN2/S3R- S26 
PERP2/S3R+ S27 
GROUND S28 
NP1 NP1 
NP2 NP2 
PTH1 PTH1 
PTH2 PTH2 
R9822 
0R2J-2-GP 
1 2
R9463 
330R2F-GP 
1 2
PC1247 
SCD1U50V3KX-GP 
1 2
SR1103 
4K7R2F-GP 
NOPOP 
1 2
R9602 
10R2F-L-GP 
1 2
Q56 
2N7002A-7-GP 
G
SD
SR1106 
4K7R2F-GP 
NOPOP 
1 2
C9524 
SCD1U16V2KX-3GP 
1 2
R9472 
4K7R2J-2-GP 
1 2
R558 
200KR2F-L-GP 1 2
R9251 
2R2010F-GP 
1 2
R572 
300KR2F-GP 1 2
PC1245 
SC22U25V6KX-GP-U 
1 2



5
5
4
4
3
3
2
2
1
1
D D
C C
B B
A A
SSD8 
SSD9 
Close to 
Connect 
Close to 
Connect 
Close to 
EU3 
N-Channel 
Close to 
EU3 
ID=-9A 
RDS(on) 
=20m ohm 
P-Channel 
Blue 
Red 
Blue 
Red 
Close to 
EU4 
N-Channel 
ID=-9A 
RDS(on) 
=20m ohm 
Close to 
EU4 
P-Channel 
N-Channel 
N-Channel 
0.01U 
0402 
X7R 
22U 
1206 
X6S 
22U 
1206 
X6S 
0.1U 
0603 
X7R 
0.01U 
0402 
X7R 
22U 
1206 
X6S 
22U 
1206 
X6S 
0.1U 
0603 
X7R 
SSD_ACT_DR8 
SSD8_CLK0_OE_n 
SSD_PRSNT_NET8 
SSD_ACT_DR9 
SSD9_CLK0_OE_n 
SSD_PRSNT_NET9 
SCL_DR8_R 
SDA_DR8_R 
SCL_DR9_R 
SDA_DR9_R 
DUALPORTEN#8 
DUALPORTEN#9 
12V_PRECH_SSD8 
12V_PRECH_SSD9 
SSD_PRSNT_NET8 
SW_SSD8_R 
SW_SSD8_N 
ATTN_LED_DR8_AND 
ATTN_LED_DR8_AND_R 
SSD_ACT_DR8 
SSD8_PWREN SSD8_PWREN_R 
P12V_MOST8_GATE_D 
P12V_MOST8_GATE 
SSD8_CLK0_OE_R_n 
ATTN_LED_DR8_R 
SSD8_CLK0_OE_n 
SSD8_CLK0_OE_MOS_n 
SSD_ACT_DR8_R 
SSD_ACT_DR8_MOS_N 
ATTN_LED_DR8_MOS_N DRV_ATTN_8 
P12V_MOST9_GATE 
SSD9_CLK0_OE_R_n 
ATTN_LED_DR9_R 
SSD9_CLK0_OE_MOS_n 
SSD_ACT_DR9_R 
SSD_ACT_DR9_MOS_N 
ATTN_LED_DR9_MOS_N DRV_ATTN_9 
SSD_PRSNT_NET9 SSD9_CLK0_OE_n 
SW_SSD9_R 
SW_SSD9_N 
ATTN_LED_DR9_AND 
ATTN_LED_DR9_AND_R 
SSD_ACT_DR9 
SSD9_PWREN SSD9_PWREN_R 
P12V_MOST9_GATE_D 
DRV_ACT_8 
DRV_ACT_9 
P3V3 
P12V_SSD8 
P3V3 
P12V_SSD9 
P3V3 
P12V_SSD8 
P3V3 
P12V_SSD9 
P3V3 
P3V3 
P3V3 
P3V3 
P12V P12V_SSD8 P12V P3V3 
P12V_SSD8 P12V 
P3V3 
P3V3 
P3V3 
P3V3 
P3V3 P3V3 
P3V3 
P3V3 
P3V3 
P3V3 
P3V3 
P12V P12V_SSD9 
P12V 
P12V_SSD9 P12V 
P12V 
P12V 
P3V3 
P3V3 
P3V3 
P3V3 
P3V3 
P3V3 
PE_RX1_DR8_n 17
PE_RX1_DR8_p 17
PE_TX3_DR8_p 17 
PE_TX3_DR8_n 17 
SDA_DR8 20
SCL_DR8 20
PE_RX4_DR8_p 17
PE_RX4_DR8_n 17
PE_RX3_DR8_p 17
PE_RX3_DR8_n 17
PE_CLK100M_dr8_2_p 22 
PE_CLK100M_dr8_2_n 22 
PE_TX2_DR8_n 17 
PE_TX2_DR8_p 17 
SSD8_PERST_N 17 
PE_TX1_DR8_p 17 
PE_TX1_DR8_n 17 
PE_CLK100M_dr8_1_p 22 
PE_CLK100M_dr8_1_n 22 
PE_RX2_DR8_n 17
PE_RX2_DR8_p 17
PE_TX4_DR8_n 17 
PE_TX4_DR8_p 17 
PE_RX1_DR9_n 17
PE_RX1_DR9_p 17
PE_TX3_DR9_p 17 
PE_TX3_DR9_n 17 
SDA_DR9 20
SCL_DR9 20
PE_RX4_DR9_p 17
PE_RX4_DR9_n 17
PE_RX3_DR9_p 17
PE_RX3_DR9_n 17
PE_CLK100M_dr9_2_p 22 
PE_CLK100M_dr9_2_n 22 
PE_TX2_DR9_n 17 
PE_TX2_DR9_p 17 
SSD9_PERST_N 17 
PE_TX1_DR9_p 17 
PE_TX1_DR9_n 17 
PE_CLK100M_dr9_1_p 22 
PE_CLK100M_dr9_1_n 22 
PE_RX2_DR9_n 17
PE_RX2_DR9_p 17
PE_TX4_DR9_n 17 
PE_TX4_DR9_p 17 
SSD_PRSNT8 22 
SSD8_PWREN 17 
ATTN_LED_DR8_N 12,17 
SSD8_CLK0_OE_R_n 17,22 
ATTN_LED_DR8_N 12,17 
ATTN_LED_DR9_N 12,17 
ATTN_LED_DR9_N 12,17 
SSD_PRSNT9 22 SSD9_CLK0_OE_R_n 17,22 
SSD9_PWREN 17 
Title 
Size Document Number Rev
Date: Sheet 
of 
Lightning_PDPB 1
SSD CNs 8-9 
A2 
12 28Thursday, March 09, 2017 
Wiwynn 
H/W R&D Dept. II 
8F,90,Sec. 1,Hsin Tai Wu Rd, 
Hsichih, Taipei Hsien 221, Taiwan, R.O.C
Title 
Size Document Number Rev
Date: Sheet 
of 
Lightning_PDPB 1
SSD CNs 8-9 
A2 
12 28Thursday, March 09, 2017 
Wiwynn 
H/W R&D Dept. II 
8F,90,Sec. 1,Hsin Tai Wu Rd, 
Hsichih, Taipei Hsien 221, Taiwan, R.O.C
Title 
Size Document Number Rev
Date: Sheet 
of 
Lightning_PDPB 1
SSD CNs 8-9 
A2 
12 28Thursday, March 09, 2017 
Wiwynn 
H/W R&D Dept. II 
8F,90,Sec. 1,Hsin Tai Wu Rd, 
Hsichih, Taipei Hsien 221, Taiwan, R.O.C
R405 0R2J-2-GP 1 2
S
S
S
G D
D
D
D
U17 
P2003EVG-GP 
1
2
3
4 5
6
7
8
Q73 
2N7002A-7-GP 
G
SD
R147 
4K7R2J-2-GP 
1 2
C9337 
SC1KP50V2KX-1GP 
1 2
R9835 
0R2J-2-GP 
1 2
R9945 
4K7R2J-2-GP 
1 2
Q66 
2N7002A-7-GP 
G
SD
PC1198 
SCD01U50V2KX-1GP 
1 2
PC1217 
SCD1U50V3KX-GP 
1 2
C9370 
SC1KP50V2KX-1GP 
1 2
R575 
300KR2F-GP 1 2
R9395 
4K7R2J-2-GP 
1 2
SR1139 
4K7R2F-GP 
1 2
PC1215 
SC22U25V6KX-GP-U 
1 2
R403 0R2J-2-GP 1 2
PC1199 
SCD1U25V3KX-GP 
1 2
Q17 
2N7002A-7-GP 
G
SD
R9943 
4K7R2J-2-GP 
1 2
C9347 
SC1KP50V2KX-1GP 
1 2
SR1137 
4K7R2F-GP 
1 2
Q67 
2N7002A-7-GP 
G
SD
D27 
RB551V30-1-GP 
KA
R9242 
2R2010F-GP 
1 2
PC1216 
SC22U25V6KX-GP-U 
1 2
R9842 
0R2J-2-GP 
1 2
R559 
200KR2F-L-GP 1 2
R9901 
1K82R2F-1-GP 
NOPOP 1 2
PC1218 
SCD01U50V2KX-1GP 
1 2
R9944 
4K7R2J-2-GP 
1 2
R9750 
4K7R2J-2-GP 
1 2
R9836 
0R2J-2-GP 
1 2
SR1107 
4K7R2F-GP 
NOPOP 
1 2R9768 
4K7R2J-2-GP 
NOPOP 
1 2
SR1138 
4K7R2J-2-GP 
1 2 R574 
300KR2F-GP 1 2
R9838 
2K2R5F-GP 
1 2
R9607 
10R2F-L-GP 
1 2
R9247 
2R2010F-GP 
1 2
C391 
SCD1U25V2KX-2-GP 
12
J9 
PCISLT68-14-GP-U1 
GROUND S1 
S0T+/PETP0 S2 
S0T-/PETN0 S3 
GROUND S4 
S0R-/PERN0 S5 
S0R+/PERP0 S6 
GROUND S7 
PCIE_A_REFCLK+ E7 
PCIE_A_REFCLK- E8 
GROUND E9 
PETP0 E10 
PETN0 E11 
GROUND E12 
PERN0 E13 
PERP0 E14 
GROUND E15 
RESERVED1 E16 
PETP3 E17 
PETN3 E18 
GROUND E19 
PERN3 E20 
PERP3 E21 
GROUND E22 
SMCLK E23 
SMDAT E24 
DUALPORTEN# E25 
PCIE_B_REFCLK+ E1 
PCIE_B_REFCLK- E2 
+3D3VAUX E3 
PCIE_B_RST E4 
PCIE_A_RST E5 
RESERVED3 E6 
WAKE# P1 
SPCIERST P2 
RSVD/CLKREQ# P3 
IFDET# P4 
GROUND P5 
GROUND P6 
+5V_PRECHARGE/NC P7 
+5V_A/NC P8 
+5V_B/NC P9 
PRSNT# P10 
ACTIVITY/SPINUP P11 
GROUND P12 
+12V_PRECHARGE P13 
+12V P14 
+12V P15 
GROUND S8 
S1T+/PETP1 S9 
S1T-/PETN1 S10 
GROUND S11 
S1R-/PERN1 S12 
S1R+/PERP1 S13 
GROUND S14 
RESERVED2 S15 
GROUND S16 
PETP1/S2T+ S17 
PETN1/S2T- S18 
GROUND S19 
PERN1/S2R- S20 
PERP1/S2R+ S21 
GROUND S22 
PETP2/S3T+ S23 
PETN2/S3T- S24 
GROUND S25 
PERN2/S3R- S26 
PERP2/S3R+ S27 
GROUND S28 
NP1 NP1 
NP2 NP2 
PTH1 PTH1 
PTH2 PTH2 
R9769 
4K7R2J-2-GP 
NOPOP 
1 2
Q74 
2N7002A-7-GP 
G
SD
Q71 
2N7002A-7-GP 
G
SD
R146 
4K7R2J-2-GP 
1 2
S
S
S
G D
D
D
D
U18 
P2003EVG-GP 
1
2
3
4 5
6
7
8
R9507 
4K7R2J-2-GP 
1 2
R407 0R2J-2-GP 1 2
R9837 
0R2J-2-GP 
1 2
R9833 
1KR2J-1-GP 
1 2
R9839 
1KR2J-1-GP 
1 2
SR1109 
4K7R2F-GP 
NOPOP 
1 2
SR1108 
4K7R2F-GP 
NOPOP 
1 2
Q16 
2N7002A-7-GP 
G
SD
R9843 
0R2J-2-GP 
1 2
R9900 
1K82R2F-1-GP 
NOPOP 
1 2
Q69 
2N7002A-7-GP 
G
SD
U205 
SN74LVC1G08DCKR-GP 
B2
A1
GND 3 Y 4
VCC 5
Q72 
2N7002A-7-GP 
G
SD
U206 
SN74LVC1G08DCKR-GP 
B2
A1
GND 3 Y 4
VCC 5
R404 0R2J-2-GP 1 2
R9920 
47KR2J-2-GP 
1 2
PC1219 
SCD1U25V3KX-GP 
1 2
R9505 
4K7R2J-2-GP 
1 2
C9339 
SC1KP50V2KX-1GP 
1 2
D26 
RB551V30-1-GP 
KA
R9921 
47KR2J-2-GP 
1 2 R9946 
4K7R2J-2-GP 
1 2
R9493 
330R2F-GP 
1 2
R9619 
4K7R2J-2-GP 
1 2
R9834 
47KR2J-2-GP 
1 2
R9428 
330R2F-GP 
1 2
SR1110 
4K7R2F-GP 
NOPOP 
1 2
R560 
200KR2F-L-GP 1 2
R9606 
10R2F-L-GP 
1 2
Q75 
2N7002A-7-GP 
G
SD
SR1140 
4K7R2J-2-GP 
1 2
PC1197 
SCD1U50V3KX-GP 
1 2
C9526 
SCD1U16V2KX-3GP 
1 2
R9840 
47KR2J-2-GP 
1 2
R9605 
10R2F-L-GP 
1 2
J8 
PCISLT68-14-GP-U1 
GROUND S1 
S0T+/PETP0 S2 
S0T-/PETN0 S3 
GROUND S4 
S0R-/PERN0 S5 
S0R+/PERP0 S6 
GROUND S7 
PCIE_A_REFCLK+ E7 
PCIE_A_REFCLK- E8 
GROUND E9 
PETP0 E10 
PETN0 E11 
GROUND E12 
PERN0 E13 
PERP0 E14 
GROUND E15 
RESERVED1 E16 
PETP3 E17 
PETN3 E18 
GROUND E19 
PERN3 E20 
PERP3 E21 
GROUND E22 
SMCLK E23 
SMDAT E24 
DUALPORTEN# E25 
PCIE_B_REFCLK+ E1 
PCIE_B_REFCLK- E2 
+3D3VAUX E3 
PCIE_B_RST E4 
PCIE_A_RST E5 
RESERVED3 E6 
WAKE# P1 
SPCIERST P2 
RSVD/CLKREQ# P3 
IFDET# P4 
GROUND P5 
GROUND P6 
+5V_PRECHARGE/NC P7 
+5V_A/NC P8 
+5V_B/NC P9 
PRSNT# P10 
ACTIVITY/SPINUP P11 
GROUND P12 
+12V_PRECHARGE P13 
+12V P14 
+12V P15 
GROUND S8 
S1T+/PETP1 S9 
S1T-/PETN1 S10 
GROUND S11 
S1R-/PERN1 S12 
S1R+/PERP1 S13 
GROUND S14 
RESERVED2 S15 
GROUND S16 
PETP1/S2T+ S17 
PETN1/S2T- S18 
GROUND S19 
PERN1/S2R- S20 
PERP1/S2R+ S21 
GROUND S22 
PETP2/S3T+ S23 
PETN2/S3T- S24 
GROUND S25 
PERN2/S3R- S26 
PERP2/S3R+ S27 
GROUND S28 
NP1 NP1 
NP2 NP2 
PTH1 PTH1 
PTH2 PTH2 
LED8 
LED-RB-4-GP 
1
3 2
4
C9527 
SCD1U16V2KX-3GP 
1 2
LED9 
LED-RB-4-GP 
1
3 2
4
Q70 
2N7002A-7-GP 
G
SD
PC1195 
SC22U25V6KX-GP-U 
1 2
R9832 
2K2R5F-GP 
1 2
C390 
SCD1U25V2KX-2-GP 
12
R9604 
10R2F-L-GP 
1 2
R9394 
100R2J-2-GP 
1 2
R9841 
0R2J-2-GP 
1 2
PC1196 
SC22U25V6KX-GP-U 
1 2
Q68 
2N7002A-7-GP 
G
SD
R9429 
100R2J-2-GP 
1 2
R9430 
4K7R2J-2-GP 
1 2



5
5
4
4
3
3
2
2
1
1
D D
C C
B B
A A
SSD10 
SSD11 
Close to 
Connect 
Close to 
Connect 
Close to 
EU1 
Blue 
Red 
Close to 
EU1 
N-Channel 
ID=-9A 
RDS(on) 
=20m ohm 
P-Channel 
Close to 
EU2 
Blue 
Red 
N-Channel 
ID=-9A 
RDS(on) 
=20m ohm 
P-Channel 
Close to 
EU2 
N-Channel 
N-Channel 
0.01U 
0402 
X7R 
22U 
1206 
X6S 
22U 
1206 
X6S 
0.1U 
0603 
X7R 
0.01U 
0402 
X7R 
22U 
1206 
X6S 
22U 
1206 
X6S 
0.1U 
0603 
X7R 
SSD_ACT_DR10 
SSD10_CLK0_OE_n 
SSD_PRSNT_NET10 
SSD_ACT_DR11 
SSD11_CLK0_OE_n 
SSD_PRSNT_NET11 
SCL_DR10_R 
SDA_DR10_R 
SCL_DR11_R 
SDA_DR11_R 
DUALPORTEN#10 
DUALPORTEN#11 
12V_PRECH_SSD10 
12V_PRECH_SSD11 
ATTN_LED_DR10_AND 
ATTN_LED_DR10_AND_R 
SSD_ACT_DR10 
SSD10_PWREN SSD10_PWREN_R 
P12V_MOST10_GATE_D 
P12V_MOST10_GATE 
SSD10_CLK0_OE_R_n 
ATTN_LED_DR10_R 
SSD10_CLK0_OE_MOS_n 
SSD_ACT_DR10_R 
SSD_ACT_DR10_MOS_N 
ATTN_LED_DR10_MOS_N DRV_ATTN_10 
DRV_ACT_10 
SSD10_CLK0_OE_n SSD_PRSNT_NET10 
SW_SSD10_N 
SW_SSD10_R 
ATTN_LED_DR11_AND 
ATTN_LED_DR11_AND_R 
SSD_ACT_DR11 
SSD11_PWREN SSD11_PWREN_R 
P12V_MOST11_GATE_D 
P12V_MOST11_GATE 
SSD11_CLK0_OE_R_n 
ATTN_LED_DR11_R 
SSD11_CLK0_OE_MOS_n 
SSD_ACT_DR11_R 
SSD_ACT_DR11_MOS_N 
ATTN_LED_DR11_MOS_N DRV_ATTN_11 
SW_SSD11_N 
SW_SSD11_R 
SSD_PRSNT_NET11 SSD11_CLK0_OE_n 
DRV_ACT_11 
P3V3 
P12V_SSD10 
P3V3 
P12V_SSD11 
P3V3 
P12V_SSD10 
P3V3 
P12V_SSD11 
P3V3 
P3V3 
P12V_SSD10 P12V 
P3V3 P3V3 
P3V3 
P3V3 
P3V3 
P3V3 
P3V3 
P12V P12V_SSD10 P12V 
P12V_SSD11 P12V 
P3V3 P3V3 
P3V3 
P3V3 
P12V P12V_SSD11 P12V 
P3V3 
P3V3 
P3V3 
P12V 
P12V 
P3V3 
P3V3 
P3V3 
P3V3 
P3V3 
P3V3 
PE_RX1_DR10_p 16
PE_RX1_DR10_n 16
PE_TX3_DR10_n 16 
PE_TX3_DR10_p 16 
SDA_DR10 20
SCL_DR10 20
PE_RX4_DR10_n 16
PE_RX4_DR10_p 16
PE_RX3_DR10_n 16
PE_RX3_DR10_p 16
PE_CLK100M_dr10_2_p 21 
PE_CLK100M_dr10_2_n 21 
PE_TX2_DR10_p 16 
PE_TX2_DR10_n 16 
SSD10_PERST_N 16 
PE_TX1_DR10_n 16 
PE_TX1_DR10_p 16 
PE_CLK100M_dr10_1_p 21 
PE_CLK100M_dr10_1_n 21 
PE_RX2_DR10_p 16
PE_RX2_DR10_n 16
PE_TX4_DR10_p 16 
PE_TX4_DR10_n 16 
PE_RX1_DR11_n 16
PE_RX1_DR11_p 16
PE_TX3_DR11_p 16 
PE_TX3_DR11_n 16 
SDA_DR11 20
SCL_DR11 20
PE_RX4_DR11_p 16
PE_RX4_DR11_n 16
PE_RX3_DR11_p 16
PE_RX3_DR11_n 16
PE_CLK100M_dr11_2_p 21 
PE_CLK100M_dr11_2_n 21 
PE_TX2_DR11_n 16 
PE_TX2_DR11_p 16 
SSD11_PERST_N 16 
PE_TX1_DR11_p 16 
PE_TX1_DR11_n 16 
PE_CLK100M_dr11_1_p 21 
PE_CLK100M_dr11_1_n 21 
PE_RX2_DR11_n 16
PE_RX2_DR11_p 16
PE_TX4_DR11_n 16 
PE_TX4_DR11_p 16 
ATTN_LED_DR10_N 13,16 
ATTN_LED_DR10_N 13,16 
SSD10_CLK0_OE_R_n 16,21 SSD_PRSNT10 21 
SSD10_PWREN 16 
ATTN_LED_DR11_N 13,16 
ATTN_LED_DR11_N 13,16 
SSD11_PWREN 16 
SSD_PRSNT11 21 SSD11_CLK0_OE_R_n 16,21 
Title 
Size Document Number Rev
Date: Sheet 
of 
Lightning_PDPB 1
SSD CNs 10-11 
A2 
13 28Thursday, March 09, 2017 
Wiwynn 
H/W R&D Dept. II 
8F,90,Sec. 1,Hsin Tai Wu Rd, 
Hsichih, Taipei Hsien 221, Taiwan, R.O.C
Title 
Size Document Number Rev
Date: Sheet 
of 
Lightning_PDPB 1
SSD CNs 10-11 
A2 
13 28Thursday, March 09, 2017 
Wiwynn 
H/W R&D Dept. II 
8F,90,Sec. 1,Hsin Tai Wu Rd, 
Hsichih, Taipei Hsien 221, Taiwan, R.O.C
Title 
Size Document Number Rev
Date: Sheet 
of 
Lightning_PDPB 1
SSD CNs 10-11 
A2 
13 28Thursday, March 09, 2017 
Wiwynn 
H/W R&D Dept. II 
8F,90,Sec. 1,Hsin Tai Wu Rd, 
Hsichih, Taipei Hsien 221, Taiwan, R.O.C
C9371 
SC1KP50V2KX-1GP 
1 2
R9437 
4K7R2J-2-GP 
1 2
U208 
SN74LVC1G08DCKR-GP 
B2
A1
GND 3 Y 4
VCC 5
C9529 
SCD1U16V2KX-3GP 
1 2 R9260 
2R2010F-GP 
1 2
S
S
S
G D
D
D
D
U19 
P2003EVG-GP 
1
2
3
4 5
6
7
8
S
S
S
G D
D
D
D
U20 
P2003EVG-GP 
1
2
3
4 5
6
7
8
PC1180 
SC22U25V6KX-GP-U 
1 2
R9948 
4K7R2J-2-GP 
1 2
U207 
SN74LVC1G08DCKR-GP 
B2
A1
GND 3 Y 4
VCC 5
Q84 
2N7002A-7-GP 
G
SD
R9849 
0R2J-2-GP 
1 2
R9609 
10R2F-L-GP 
1 2
R9752 
4K7R2J-2-GP 
1 2
R408 0R2J-2-GP 1 2
PC1183 
SCD01U50V2KX-1GP 
1 2
R9850 
2K2R5F-GP 
1 2
PC1224 
SCD1U25V3KX-GP 
1 2
Q79 
2N7002A-7-GP 
G
SD
R9950 
4K7R2J-2-GP 
1 2
R123 
4K7R2J-2-GP 
1 2
R9751 
4K7R2J-2-GP 
1 2
R9851 
1KR2J-1-GP 
1 2
R9435 
330R2F-GP 
1 2
SR1142 
4K7R2J-2-GP 
1 2
R9845 
1KR2J-1-GP 
1 2
PC1184 
SCD1U25V3KX-GP 
1 2
R117 
330R2F-GP 
1 2
R9844 
2K2R5F-GP 
1 2
R410 0R2J-2-GP 1 2
R561 
200KR2F-L-GP 1 2
R9241 
2R2010F-GP 
1 2
R562 
200KR2F-L-GP 1 2
LED11 
LED-RB-4-GP 
1
3 2
4
C393 
SCD1U25V2KX-2-GP 
12
SR1113 
4K7R2F-GP 
NOPOP 
1 2
C132 
SC1KP50V2KX-1GP 
1 2
R9902 
1K82R2F-1-GP 
NOPOP 
1 2
LED10 
LED-RB-4-GP 
1
3 2
4
Q85 
2N7002A-7-GP 
G
SD
R9770 
4K7R2J-2-GP 
NOPOP 
1 2
Q80 
2N7002A-7-GP 
G
SD
R9852 
47KR2J-2-GP 
1 2
R9436 
100R2J-2-GP 
1 2
J11 
PCISLT68-14-GP-U1 
GROUND S1 
S0T+/PETP0 S2 
S0T-/PETN0 S3 
GROUND S4 
S0R-/PERN0 S5 
S0R+/PERP0 S6 
GROUND S7 
PCIE_A_REFCLK+ E7 
PCIE_A_REFCLK- E8 
GROUND E9 
PETP0 E10 
PETN0 E11 
GROUND E12 
PERN0 E13 
PERP0 E14 
GROUND E15 
RESERVED1 E16 
PETP3 E17 
PETN3 E18 
GROUND E19 
PERN3 E20 
PERP3 E21 
GROUND E22 
SMCLK E23 
SMDAT E24 
DUALPORTEN# E25 
PCIE_B_REFCLK+ E1 
PCIE_B_REFCLK- E2 
+3D3VAUX E3 
PCIE_B_RST E4 
PCIE_A_RST E5 
RESERVED3 E6 
WAKE# P1 
SPCIERST P2 
RSVD/CLKREQ# P3 
IFDET# P4 
GROUND P5 
GROUND P6 
+5V_PRECHARGE/NC P7 
+5V_A/NC P8 
+5V_B/NC P9 
PRSNT# P10 
ACTIVITY/SPINUP P11 
GROUND P12 
+12V_PRECHARGE P13 
+12V P14 
+12V P15 
GROUND S8 
S1T+/PETP1 S9 
S1T-/PETN1 S10 
GROUND S11 
S1R-/PERN1 S12 
S1R+/PERP1 S13 
GROUND S14 
RESERVED2 S15 
GROUND S16 
PETP1/S2T+ S17 
PETN1/S2T- S18 
GROUND S19 
PERN1/S2R- S20 
PERP1/S2R+ S21 
GROUND S22 
PETP2/S3T+ S23 
PETN2/S3T- S24 
GROUND S25 
PERN2/S3R- S26 
PERP2/S3R+ S27 
GROUND S28 
NP1 NP1 
NP2 NP2 
PTH1 PTH1 
PTH2 PTH2 
R148 
4K7R2J-2-GP 
1 2
R149 
4K7R2J-2-GP 
1 2
R9610 
10R2F-L-GP 
1 2
R115 
100R2J-2-GP 
1 2
R9846 
47KR2J-2-GP 
1 2
SR1114 
4K7R2F-GP 
NOPOP 
1 2
R9853 
0R2J-2-GP 
1 2 R577 
300KR2F-GP 1 2
Q18 
2N7002A-7-GP 
G
SD
Q83 
2N7002A-7-GP 
G
SD
R9515 
4K7R2J-2-GP 
1 2
R9847 
0R2J-2-GP 
1 2
R409 0R2J-2-GP 1 2
R9608 
10R2F-L-GP 
1 2
SR1111 
4K7R2F-GP 
NOPOP 
1 2
R576 
300KR2F-GP 1 2
Q19 
2N7002A-7-GP 
G
SD
Q78 
2N7002A-7-GP 
G
SD
SR1144 
4K7R2J-2-GP 
1 2
PC1222 
SCD1U50V3KX-GP 
1 2
D28 
RB551V30-1-GP 
KA
SR1143 
4K7R2F-GP 
1 2
C9349 
SC1KP50V2KX-1GP 
1 2
R9611 
10R2F-L-GP 
1 2
R9903 
1K82R2F-1-GP 
NOPOP 
1 2
PC1220 
SC22U25V6KX-GP-U 
1 2
SR1141 
4K7R2F-GP 
1 2
R9922 
47KR2J-2-GP 
1 2
Q81 
2N7002A-7-GP 
G
SD
R9771 
4K7R2J-2-GP 
NOPOP 
1 2
J10 
PCISLT68-14-GP-U1 
GROUND S1 
S0T+/PETP0 S2 
S0T-/PETN0 S3 
GROUND S4 
S0R-/PERN0 S5 
S0R+/PERP0 S6 
GROUND S7 
PCIE_A_REFCLK+ E7 
PCIE_A_REFCLK- E8 
GROUND E9 
PETP0 E10 
PETN0 E11 
GROUND E12 
PERN0 E13 
PERP0 E14 
GROUND E15 
RESERVED1 E16 
PETP3 E17 
PETN3 E18 
GROUND E19 
PERN3 E20 
PERP3 E21 
GROUND E22 
SMCLK E23 
SMDAT E24 
DUALPORTEN# E25 
PCIE_B_REFCLK+ E1 
PCIE_B_REFCLK- E2 
+3D3VAUX E3 
PCIE_B_RST E4 
PCIE_A_RST E5 
RESERVED3 E6 
WAKE# P1 
SPCIERST P2 
RSVD/CLKREQ# P3 
IFDET# P4 
GROUND P5 
GROUND P6 
+5V_PRECHARGE/NC P7 
+5V_A/NC P8 
+5V_B/NC P9 
PRSNT# P10 
ACTIVITY/SPINUP P11 
GROUND P12 
+12V_PRECHARGE P13 
+12V P14 
+12V P15 
GROUND S8 
S1T+/PETP1 S9 
S1T-/PETN1 S10 
GROUND S11 
S1R-/PERN1 S12 
S1R+/PERP1 S13 
GROUND S14 
RESERVED2 S15 
GROUND S16 
PETP1/S2T+ S17 
PETN1/S2T- S18 
GROUND S19 
PERN1/S2R- S20 
PERP1/S2R+ S21 
GROUND S22 
PETP2/S3T+ S23 
PETN2/S3T- S24 
GROUND S25 
PERN2/S3R- S26 
PERP2/S3R+ S27 
GROUND S28 
NP1 NP1 
NP2 NP2 
PTH1 PTH1 
PTH2 PTH2 
R412 0R2J-2-GP 1 2
D29 
RB551V30-1-GP 
KA
C392 
SCD1U25V2KX-2-GP 
12
R9923 
47KR2J-2-GP 
1 2
Q77 
2N7002A-7-GP 
G
SD
PC1221 
SC22U25V6KX-GP-U 
1 2
SR1112 
4K7R2F-GP 
NOPOP 
1 2
Q82 
2N7002A-7-GP 
G
SD
C131 
SC1KP50V2KX-1GP 
1 2
PC1182 
SCD1U50V3KX-GP 
1 2
R9854 
0R2J-2-GP 
1 2
R9848 
0R2J-2-GP 
1 2
PC1223 
SCD01U50V2KX-1GP 
1 2
Q76 
2N7002A-7-GP 
G
SD
R9947 
4K7R2J-2-GP 
1 2
C9528 
SCD1U16V2KX-3GP 
1 2
R124 
4K7R2J-2-GP 
1 2
R9949 
4K7R2J-2-GP 
1 2
PC1181 
SC22U25V6KX-GP-U 
1 2
R9855 
0R2J-2-GP 
1 2



5
5
4
4
3
3
2
2
1
1
D D
C C
B B
A A
SSD12 
SSD13 
Close to 
Connect 
Close to 
Connect 
Close to 
EU3 
ID=-9A 
RDS(on) 
=20m ohm 
P-Channel 
Close to 
EU3 
N-Channel 
Blue 
Red 
Close to 
EU3 
ID=-9A 
RDS(on) 
=20m ohm 
P-Channel N-Channel 
Blue 
Red 
Close to 
EU3 
N-Channel 
N-Channel 
0.01U 
0402 
X7R 
22U 
1206 
X6S 
22U 
1206 
X6S 
0.1U 
0603 
X7R 
0.01U 
0402 
X7R 
22U 
1206 
X6S 
22U 
1206 
X6S 
0.1U 
0603 
X7R 
SSD_ACT_DR12 
SSD12_CLK0_OE_n 
SSD_PRSNT_NET12 
SSD_ACT_DR13 
SSD13_CLK0_OE_n 
SSD_PRSNT_NET13 
SCL_DR12_R 
SDA_DR12_R 
SCL_DR13_R 
SDA_DR13_R 
DUALPORTEN#12 
DUALPORTEN#13 
12V_PRECH_SSD12 
12V_PRECH_SSD13 
SW_SSD12_R 
SW_SSD12_N 
ATTN_LED_DR12_AND 
ATTN_LED_DR12_AND_R 
SSD_ACT_DR12 
SSD12_PWREN SSD12_PWREN_R 
P12V_MOST12_GATE_D 
P12V_MOST12_GATE 
SSD12_CLK0_OE_R_n 
ATTN_LED_DR12_R 
SSD12_CLK0_OE_MOS_n 
SSD_ACT_DR12_R 
SSD_ACT_DR12_MOS_N 
ATTN_LED_DR12_MOS_N DRV_ATTN_12 
SSD12_CLK0_OE_n SSD_PRSNT_NET12 
SW_SSD13_R 
SW_SSD13_N 
ATTN_LED_DR13_AND 
ATTN_LED_DR13_AND_R 
SSD_ACT_DR13 
SSD13_PWREN SSD13_PWREN_R 
P12V_MOST13_GATE_D 
P12V_MOST13_GATE 
SSD13_CLK0_OE_R_n 
ATTN_LED_DR13_R 
SSD13_CLK0_OE_MOS_n 
SSD_ACT_DR13_R 
SSD_ACT_DR13_MOS_N 
ATTN_LED_DR13_MOS_N DRV_ATTN_13 
SSD_PRSNT_NET13 SSD13_CLK0_OE_n 
DRV_ACT_12 
DRV_ACT_13 
P3V3 P12V_SSD12 
P3V3 
P12V_SSD13 
P3V3 
P12V_SSD12 
P3V3 
P12V_SSD13 
P3V3 
P3V3 
P12V P12V_SSD12 P12V 
P12V_SSD12 P12V 
P3V3 P3V3 
P3V3 
P3V3 P3V3 
P3V3 
P3V3 
P12V P12V_SSD13 P12V 
P12V_SSD13 P12V 
P3V3 P3V3 
P3V3 
P3V3 
P3V3 
P3V3 
P3V3 
P12V 
P12V 
P3V3 
P3V3 
P3V3 
P3V3 
P3V3 
P3V3 
PE_RX1_DR12_n 17
PE_RX1_DR12_p 17
PE_TX3_DR12_p 17 
PE_TX3_DR12_n 17 
SDA_DR12 20
SCL_DR12 20
PE_RX4_DR12_p 17
PE_RX4_DR12_n 17
PE_RX3_DR12_p 17
PE_RX3_DR12_n 17
PE_CLK100M_dr12_2_p 22 
PE_CLK100M_dr12_2_n 22 
PE_TX2_DR12_n 17 
PE_TX2_DR12_p 17 
SSD12_PERST_N 16 
PE_TX1_DR12_p 17 
PE_TX1_DR12_n 17 
PE_CLK100M_dr12_1_p 22 
PE_CLK100M_dr12_1_n 22 
PE_RX2_DR12_n 17
PE_RX2_DR12_p 17
PE_TX4_DR12_n 17 
PE_TX4_DR12_p 17 
PE_RX1_DR13_n 17
PE_RX1_DR13_p 17
PE_TX3_DR13_p 17 
PE_TX3_DR13_n 17 
SDA_DR13 20
SCL_DR13 20
PE_RX4_DR13_p 17
PE_RX4_DR13_n 17
PE_RX3_DR13_p 17
PE_RX3_DR13_n 17
PE_CLK100M_dr13_2_p 22 
PE_CLK100M_dr13_2_n 22 
PE_TX2_DR13_n 17 
PE_TX2_DR13_p 17 
SSD13_PERST_N 17 
PE_TX1_DR13_p 17 
PE_TX1_DR13_n 17 
PE_CLK100M_dr13_1_p 22 
PE_CLK100M_dr13_1_n 22 
PE_RX2_DR13_n 17
PE_RX2_DR13_p 17
PE_TX4_DR13_n 17 
PE_TX4_DR13_p 17 
SSD_PRSNT12 22 
SSD12_PWREN 16 
ATTN_LED_DR12_N 14,16 
ATTN_LED_DR12_N 14,16 
SSD12_CLK0_OE_R_n 16,22 
SSD13_PWREN 17 
ATTN_LED_DR13_N 14,17 
ATTN_LED_DR13_N 14,17 
SSD_PRSNT13 22 SSD13_CLK0_OE_R_n 17,22 
Title 
Size Document Number Rev
Date: Sheet 
of 
Lightning_PDPB 1
SSD CNs 12-13 
A2 
14 28Thursday, March 09, 2017 
Wiwynn 
H/W R&D Dept. II 
8F,90,Sec. 1,Hsin Tai Wu Rd, 
Hsichih, Taipei Hsien 221, Taiwan, R.O.C
Title 
Size Document Number Rev
Date: Sheet 
of 
Lightning_PDPB 1
SSD CNs 12-13 
A2 
14 28Thursday, March 09, 2017 
Wiwynn 
H/W R&D Dept. II 
8F,90,Sec. 1,Hsin Tai Wu Rd, 
Hsichih, Taipei Hsien 221, Taiwan, R.O.C
Title 
Size Document Number Rev
Date: Sheet 
of 
Lightning_PDPB 1
SSD CNs 12-13 
A2 
14 28Thursday, March 09, 2017 
Wiwynn 
H/W R&D Dept. II 
8F,90,Sec. 1,Hsin Tai Wu Rd, 
Hsichih, Taipei Hsien 221, Taiwan, R.O.C
R415 0R2J-2-GP 1 2
R9858 
2K2R5F-GP 
1 2
SR1115 
4K7R2F-GP 
NOPOP 
1 2
R9615 
10R2F-L-GP 
1 2
R9479 
4K7R2J-2-GP 
1 2
R9868 
0R2J-2-GP 
1 2
U210 
SN74LVC1G08DCKR-GP 
B2
A1
GND 3 Y 4
VCC 5
Q20 
2N7002A-7-GP 
G
SD
R9952 
4K7R2J-2-GP 
1 2
Q91 
2N7002A-7-GP 
G
SD
R9859 
1KR2J-1-GP 
1 2
SR1146 
4K7R2J-2-GP 
1 2
D30 
RB551V30-1-GP 
KA
U209 
SN74LVC1G08DCKR-GP 
B2
A1
GND 3 Y 4
VCC 5
R564 
200KR2F-L-GP 1 2
R9477 
330R2F-GP 
1 2
R9754 
4K7R2J-2-GP 
1 2
SR1147 
4K7R2F-GP 
1 2
PC1254 
SCD1U25V3KX-GP 
1 2
C9530 
SCD1U16V2KX-3GP 
1 2
R9614 
10R2F-L-GP 
1 2
SR1116 
4K7R2F-GP 
NOPOP 
1 2
Q92 
2N7002A-7-GP 
G
SD
R9869 
0R2J-2-GP 
1 2
LED12 
LED-RB-4-GP 
1
3 2
4
R151 
4K7R2J-2-GP 
1 2
Q90 
2N7002A-7-GP 
G
SD
C9531 
SCD1U16V2KX-3GP 
1 2
R9860 
47KR2J-2-GP 
1 2
R9478 
100R2J-2-GP 
1 2
R413 0R2J-2-GP 1 2
C9373 
SC1KP50V2KX-1GP 
1 2
Q21 
2N7002A-7-GP 
G
SD
R9613 
10R2F-L-GP 
1 2
R9951 
4K7R2J-2-GP 
1 2
S
S
S
G D
D
D
D
U21 
P2003EVG-GP 
1
2
3
4 5
6
7
8
R9612 
10R2F-L-GP 
1 2
PC1252 
SCD1U50V3KX-GP 
1 2
R9246 
2R2010F-GP 
1 2
R581 
300KR2F-GP 1 2
C9345 
SC1KP50V2KX-1GP 
1 2
J13 
PCISLT68-14-GP-U1 
GROUND S1 
S0T+/PETP0 S2 
S0T-/PETN0 S3 
GROUND S4 
S0R-/PERN0 S5 
S0R+/PERP0 S6 
GROUND S7 
PCIE_A_REFCLK+ E7 
PCIE_A_REFCLK- E8 
GROUND E9 
PETP0 E10 
PETN0 E11 
GROUND E12 
PERN0 E13 
PERP0 E14 
GROUND E15 
RESERVED1 E16 
PETP3 E17 
PETN3 E18 
GROUND E19 
PERN3 E20 
PERP3 E21 
GROUND E22 
SMCLK E23 
SMDAT E24 
DUALPORTEN# E25 
PCIE_B_REFCLK+ E1 
PCIE_B_REFCLK- E2 
+3D3VAUX E3 
PCIE_B_RST E4 
PCIE_A_RST E5 
RESERVED3 E6 
WAKE# P1 
SPCIERST P2 
RSVD/CLKREQ# P3 
IFDET# P4 
GROUND P5 
GROUND P6 
+5V_PRECHARGE/NC P7 
+5V_A/NC P8 
+5V_B/NC P9 
PRSNT# P10 
ACTIVITY/SPINUP P11 
GROUND P12 
+12V_PRECHARGE P13 
+12V P14 
+12V P15 
GROUND S8 
S1T+/PETP1 S9 
S1T-/PETN1 S10 
GROUND S11 
S1R-/PERN1 S12 
S1R+/PERP1 S13 
GROUND S14 
RESERVED2 S15 
GROUND S16 
PETP1/S2T+ S17 
PETN1/S2T- S18 
GROUND S19 
PERN1/S2R- S20 
PERP1/S2R+ S21 
GROUND S22 
PETP2/S3T+ S23 
PETN2/S3T- S24 
GROUND S25 
PERN2/S3R- S26 
PERP2/S3R+ S27 
GROUND S28 
NP1 NP1 
NP2 NP2 
PTH1 PTH1 
PTH2 PTH2 
R9772 
4K7R2J-2-GP NOPOP 
1 2
C395 
SCD1U25V2KX-2-GP 
12
R9954 
4K7R2J-2-GP 
1 2
Q94 
2N7002A-7-GP 
G
SD
PC1250 
SC22U25V6KX-GP-U 
1 2
R9861 
0R2J-2-GP 
1 2
SR1148 
4K7R2J-2-GP 
1 2
Q88 
2N7002A-7-GP 
G
SD
D31 
RB551V30-1-GP 
KA
PC1212 
SCD1U50V3KX-GP 
1 2
R416 0R2J-2-GP 1 2
PC1253 
SCD01U50V2KX-1GP 
1 2
R9865 
1KR2J-1-GP 
1 2
Q86 
2N7002A-7-GP 
G
SD
PC1210 
SC22U25V6KX-GP-U 
1 2
C9361 
SC1KP50V2KX-1GP 
1 2
R9421 
330R2F-GP 
1 2
SR1145 
4K7R2F-GP 
1 2
PC1251 
SC22U25V6KX-GP-U 
1 2
C9372 
SC1KP50V2KX-1GP 
1 2
R9773 
4K7R2J-2-GP 
NOPOP 
1 2
PC1211 
SC22U25V6KX-GP-U 
1 2
R563 
200KR2F-L-GP 1 2
R9517 
4K7R2J-2-GP 
1 2
SR1117 
4K7R2F-GP 
NOPOP 
1 2
R9862 
0R2J-2-GP 
1 2
PC1213 
SCD01U50V2KX-1GP 
1 2
R9753 
4K7R2J-2-GP 
1 2
R9252 
2R2010F-GP 
1 2
R9423 
4K7R2J-2-GP 
1 2
R9587 
4K7R2J-2-GP 
1 2
Q87 
2N7002A-7-GP 
G
SD
J12 
PCISLT68-14-GP-U1 
GROUND S1 
S0T+/PETP0 S2 
S0T-/PETN0 S3 
GROUND S4 
S0R-/PERN0 S5 
S0R+/PERP0 S6 
GROUND S7 
PCIE_A_REFCLK+ E7 
PCIE_A_REFCLK- E8 
GROUND E9 
PETP0 E10 
PETN0 E11 
GROUND E12 
PERN0 E13 
PERP0 E14 
GROUND E15 
RESERVED1 E16 
PETP3 E17 
PETN3 E18 
GROUND E19 
PERN3 E20 
PERP3 E21 
GROUND E22 
SMCLK E23 
SMDAT E24 
DUALPORTEN# E25 
PCIE_B_REFCLK+ E1 
PCIE_B_REFCLK- E2 
+3D3VAUX E3 
PCIE_B_RST E4 
PCIE_A_RST E5 
RESERVED3 E6 
WAKE# P1 
SPCIERST P2 
RSVD/CLKREQ# P3 
IFDET# P4 
GROUND P5 
GROUND P6 
+5V_PRECHARGE/NC P7 
+5V_A/NC P8 
+5V_B/NC P9 
PRSNT# P10 
ACTIVITY/SPINUP P11 
GROUND P12 
+12V_PRECHARGE P13 
+12V P14 
+12V P15 
GROUND S8 
S1T+/PETP1 S9 
S1T-/PETN1 S10 
GROUND S11 
S1R-/PERN1 S12 
S1R+/PERP1 S13 
GROUND S14 
RESERVED2 S15 
GROUND S16 
PETP1/S2T+ S17 
PETN1/S2T- S18 
GROUND S19 
PERN1/S2R- S20 
PERP1/S2R+ S21 
GROUND S22 
PETP2/S3T+ S23 
PETN2/S3T- S24 
GROUND S25 
PERN2/S3R- S26 
PERP2/S3R+ S27 
GROUND S28 
NP1 NP1 
NP2 NP2 
PTH1 PTH1 
PTH2 PTH2 
Q95 
2N7002A-7-GP 
G
SD
R9866 
47KR2J-2-GP 
1 2
R9953 
4K7R2J-2-GP 
1 2
S
S
S
G D
D
D
D
U22 
P2003EVG-GP 
1
2
3
4 5
6
7
8
R9904 
1K82R2F-1-GP 
NOPOP 
1 2
R9905 
1K82R2F-1-GP 
NOPOP 
1 2
R9863 
0R2J-2-GP 
1 2
R414 0R2J-2-GP 1 2
LED13 
LED-RB-4-GP 
1
3 2
4
R9864 
2K2R5F-GP 
1 2
R150 
4K7R2J-2-GP 
1 2
R9867 
0R2J-2-GP 
1 2
C394 
SCD1U25V2KX-2-GP 
12
R9924 
47KR2J-2-GP 
1 2
SR1118 
4K7R2F-GP 
NOPOP 
1 2
R9422 
100R2J-2-GP 
1 2
PC1214 
SCD1U25V3KX-GP 
1 2
R580 
300KR2F-GP 1 2
Q93 
2N7002A-7-GP 
G
SD
R9925 
47KR2J-2-GP 
1 2
Q89 
2N7002A-7-GP 
G
SD



5
5
4
4
3
3
2
2
1
1
D D
C C
B B
A A
SSD14 
Close to 
Connect 
Close to 
EU4 
N-Channel 
Blue 
Red 
ID=-9A 
RDS(on) 
=20m ohm 
P-Channel 
Close to 
EU4 
PDPB LED Status 
N-Channel 
0.01U 
0402 
X7R 
22U 
1206 
X6S 
22U 
1206 
X6S 
0.1U 
0603 
X7R 
SSD_ACT_DR14 
SSD14_CLK0_OE_n 
SSD_PRSNT_NET14 
SCL_DR14_R 
SDA_DR14_R 
DUALPORTEN#14 
12V_PRECH_SSD14 
SSD_PRSNT_NET14 
ATTN_LED_DR14_AND 
ATTN_LED_DR14_AND_R 
SSD_ACT_DR14 
SSD14_PWREN SSD14_PWREN_R 
P12V_MOST14_GATE_D 
P12V_MOST14_GATE 
SSD14_CLK0_OE_R_n 
ATTN_LED_DR14_R 
SSD14_CLK0_OE_MOS_n 
SSD_ACT_DR14_R 
SSD_ACT_DR14_MOS_N 
ATTN_LED_DR14_MOS_N DRV_ATTN_14 
DRV_ACT_14 
SW_SSD14_R 
SW_SSD14_N 
SSD14_CLK0_OE_n 
P3V3 P12V_SSD14 
P3V3 
P12V_SSD14 
P3V3 
P3V3 
P12V_SSD14 P12V 
P3V3 P3V3 
P3V3 
P3V3 
P12V P12V_SSD14 P12V 
P3V3 
P3V3 
P12V 
P3V3 
P3V3 
P3V3 
PE_RX1_DR14_n 17
PE_RX1_DR14_p 17
PE_TX3_DR14_p 17 
PE_TX3_DR14_n 17 
SDA_DR14 20
SCL_DR14 20
PE_RX4_DR14_p 17
PE_RX4_DR14_n 17
PE_RX3_DR14_p 17
PE_RX3_DR14_n 17
PE_CLK100M_dr14_2_p 22 
PE_CLK100M_dr14_2_n 22 
PE_TX2_DR14_n 17 
PE_TX2_DR14_p 17 
SSD14_PERST_N 17 
PE_TX1_DR14_p 17 
PE_TX1_DR14_n 17 
PE_CLK100M_dr14_1_p 22 
PE_CLK100M_dr14_1_n 22 
PE_RX2_DR14_n 17
PE_RX2_DR14_p 17
PE_TX4_DR14_n 17 
PE_TX4_DR14_p 17 
SSD_PRSNT14 22 
ATTN_LED_DR14_N 15,17 
ATTN_LED_DR14_N 15,17 
SSD14_PWREN 17 
SSD14_CLK0_OE_R_n 17,22 
Title 
Size Document Number Rev
Date: Sheet 
of 
Lightning_PDPB 1
SSD CNs 14 
A2 
15 28Thursday, March 09, 2017 
Wiwynn 
H/W R&D Dept. II 
8F,90,Sec. 1,Hsin Tai Wu Rd, 
Hsichih, Taipei Hsien 221, Taiwan, R.O.C
Title 
Size Document Number Rev
Date: Sheet 
of 
Lightning_PDPB 1
SSD CNs 14 
A2 
15 28Thursday, March 09, 2017 
Wiwynn 
H/W R&D Dept. II 
8F,90,Sec. 1,Hsin Tai Wu Rd, 
Hsichih, Taipei Hsien 221, Taiwan, R.O.C
Title 
Size Document Number Rev
Date: Sheet 
of 
Lightning_PDPB 1
SSD CNs 14 
A2 
15 28Thursday, March 09, 2017 
Wiwynn 
H/W R&D Dept. II 
8F,90,Sec. 1,Hsin Tai Wu Rd, 
Hsichih, Taipei Hsien 221, Taiwan, R.O.C
Q100 
2N7002A-7-GP 
G
SD
R9872 
47KR2J-2-GP 
1 2
R417 0R2J-2-GP 1 2
R9926 
47KR2J-2-GP 
1 2
SR1120 
4K7R2F-GP 
NOPOP 
1 2
R9458 
4K7R2J-2-GP 
1 2
S
S
S
G D
D
D
D
U23 
P2003EVG-GP 
1
2
3
4 5
6
7
8
R9873 
0R2J-2-GP 
1 2
R9955 
4K7R2J-2-GP 
1 2
R9755 
4K7R2J-2-GP 
1 2Q98 
2N7002A-7-GP 
G
SD
R9249 
2R2010F-GP 
1 2
C9374 
SC1KP50V2KX-1GP 
1 2
SR1149 
4K7R2F-GP 
1 2
R9956 
4K7R2J-2-GP 
1 2
R9874 
0R2J-2-GP 
1 2
Q96 
2N7002A-7-GP 
G
SD
C9532 
SCD1U16V2KX-3GP 
1 2
R582 
200KR2F-L-GP 1 2
R9875 
0R2J-2-GP 
1 2
PC1232 
SCD1U50V3KX-GP 
1 2
Q97 
2N7002A-7-GP 
G
SD
R9616 
10R2F-L-GP 
1 2
U211 
SN74LVC1G08DCKR-GP 
B2
A1
GND 3 Y 4
VCC 5
PC1230 
SC22U25V6KX-GP-U 
1 2
C9355 
SC1KP50V2KX-1GP 
1 2
R152 
4K7R2J-2-GP 
1 2
R418 0R2J-2-GP 1 2
PC1231 
SC22U25V6KX-GP-U 
1 2
PC1234 
SCD1U25V3KX-GP 
1 2
Q99 
2N7002A-7-GP 
G
SD
R583 
300KR2F-GP 1 2
J14 
PCISLT68-14-GP-U1 
GROUND S1 
S0T+/PETP0 S2 
S0T-/PETN0 S3 
GROUND S4 
S0R-/PERN0 S5 
S0R+/PERP0 S6 
GROUND S7 
PCIE_A_REFCLK+ E7 
PCIE_A_REFCLK- E8 
GROUND E9 
PETP0 E10 
PETN0 E11 
GROUND E12 
PERN0 E13 
PERP0 E14 
GROUND E15 
RESERVED1 E16 
PETP3 E17 
PETN3 E18 
GROUND E19 
PERN3 E20 
PERP3 E21 
GROUND E22 
SMCLK E23 
SMDAT E24 
DUALPORTEN# E25 
PCIE_B_REFCLK+ E1 
PCIE_B_REFCLK- E2 
+3D3VAUX E3 
PCIE_B_RST E4 
PCIE_A_RST E5 
RESERVED3 E6 
WAKE# P1 
SPCIERST P2 
RSVD/CLKREQ# P3 
IFDET# P4 
GROUND P5 
GROUND P6 
+5V_PRECHARGE/NC P7 
+5V_A/NC P8 
+5V_B/NC P9 
PRSNT# P10 
ACTIVITY/SPINUP P11 
GROUND P12 
+12V_PRECHARGE P13 
+12V P14 
+12V P15 
GROUND S8 
S1T+/PETP1 S9 
S1T-/PETN1 S10 
GROUND S11 
S1R-/PERN1 S12 
S1R+/PERP1 S13 
GROUND S14 
RESERVED2 S15 
GROUND S16 
PETP1/S2T+ S17 
PETN1/S2T- S18 
GROUND S19 
PERN1/S2R- S20 
PERP1/S2R+ S21 
GROUND S22 
PETP2/S3T+ S23 
PETN2/S3T- S24 
GROUND S25 
PERN2/S3R- S26 
PERP2/S3R+ S27 
GROUND S28 
NP1 NP1 
NP2 NP2 
PTH1 PTH1 
PTH2 PTH2 
PC1233 
SCD01U50V2KX-1GP 
1 2
R9906 
1K82R2F-1-GP 
NOPOP 
1 2
SR1150 
4K7R2J-2-GP 
1 2
R9870 
2K2R5F-GP 
1 2
R9456 
330R2F-GP 
1 2
Q22 
2N7002A-7-GP 
G
SD
R9871 
1KR2J-1-GP 
1 2
R9774 
4K7R2J-2-GP 
NOPOP 
1 2
R9457 
100R2J-2-GP 
1 2
SR1119 
4K7R2F-GP 
NOPOP 
1 2
C396 
SCD1U25V2KX-2-GP 
12
D32 
RB551V30-1-GP 
KA
LED14 
LED-RB-4-GP 
1
3 2
4
R9617 
10R2F-L-GP 
1 2
R9589 
4K7R2J-2-GP 
1 2



5
5
4
4
3
3
2
2
1
1
D D
C C
B B
A A
DPB H/W REV setting 
1:not mated 
0:Mated 
CARD EDGE CONN1 CARD EDGE CONN2 
22U 
1206 
X6S 
22U 
1206 
X6S 
22U 
1206 
X6S 
22U 
1206 
X6S 
0.1U 
0603 
X7R 
0.1U 
0603 
X7R 
0.01U 
0402 
X7R 
0.01U 
0402 
X7R 
Close to J17 
Close to J17 
Close to J17 
Close to J17 
Note:Pin swap to optimize PDPB routing. 
SELF_TRAY_PRESENT_R 
DPB_HW_REVISION 
DPB_HW_REVISION 
PCIE_MATED#_A 
PE_100M_CLK1_C_n 
PE_100M_CLK1_C_p 
PE_100M_CLK2_C_p 
PE_100M_CLK2_C_n 
PE_100M_CLK3_C_p 
PE_100M_CLK3_C_n 
PE_100M_CLK4_C_p 
PE_100M_CLK4_C_n 
P12V P12V P12V P12V 
P3V3 
ATTN_LED_DR0_N 8
PE_RX2_DR0_p 8
PE_RX2_DR0_n 8
PE_RX3_DR0_p 8
PE_RX3_DR0_n 8
PE_RX4_DR0_p 8
PE_RX4_DR0_n 8
PE_RX1_DR0_p 8
PE_RX1_DR0_n 8
ATTN_LED_DR3_N 9
SSD6_CLK0_OE_R_n 11,21 
ATTN_LED_DR1_N 8
ATTN_LED_DR7_N 11 
ATTN_LED_DR2_N 9
ATTN_LED_DR6_N 11 
SAS_I2C_B_BUF_SCL_R 19 
SAS_I2C_B_BUF_SDA_R 19 
BMC_I2C_SCL_BUF_9 19,20,21 
BMC_I2C_SDA_BUF_9 19,20,21 
SAS_I2C_C_BUF_SCL_R 19 
SAS_I2C_C_BUF_SDA_R 19 
BMC_I2C_SCL_BUF_8 19,20,22 
BMC_I2C_SDA_BUF_8 19,20,22 
PEER_1A&2A_HB 18 
SELF_1A&2A_HB 18 
SELF_TRAY_PRESENT 18 
FCB_HW_REVISION 18 
PEER_TRAY_PRESENT 18 
PE_TX1_DR1_p 8
PE_TX1_DR1_n 8
PE_TX2_DR1_n 8
PE_TX2_DR1_p 8
PE_TX3_DR1_n 8
PE_TX3_DR1_p 8
PE_TX4_DR1_n 8
PE_TX4_DR1_p 8
PE_RX1_DR1_n 8
PE_RX1_DR1_p 8
PE_RX2_DR1_n 8
PE_RX2_DR1_p 8
PE_RX3_DR1_p 8
PE_RX3_DR1_n 8
PE_RX4_DR1_n 8
PE_RX4_DR1_p 8
PE_TX2_DR10_p 13 
PE_TX2_DR10_n 13 
PE_TX1_DR10_n 13 
PE_TX1_DR10_p 13 
PE_TX3_DR10_p 13 
PE_TX3_DR10_n 13 
PE_TX4_DR10_n 13 
PE_TX4_DR10_p 13 
PE_RX4_DR10_n 13 
PE_RX4_DR10_p 13 
PE_RX1_DR10_n 13 
PE_RX1_DR10_p 13 
PE_RX2_DR10_p 13 
PE_RX2_DR10_n 13 
PE_RX3_DR10_n 13 
PE_RX3_DR10_p 13 
PE_TX1_DR0_p 8
PE_TX1_DR0_n 8
PE_TX2_DR0_n 8
PE_TX2_DR0_p 8
PE_TX3_DR0_n 8
PE_TX3_DR0_p 8
PE_TX4_DR0_p 8
PE_TX4_DR0_n 8
PE_TX2_DR5_p 10 
PE_TX1_DR5_p 10 
PE_TX1_DR5_n 10 
PE_TX2_DR5_n 10 
PE_TX3_DR5_n 10 
PE_TX3_DR5_p 10 
PE_TX4_DR5_p 10 
PE_TX4_DR5_n 10 
PE_RX1_DR5_p 10 
PE_RX1_DR5_n 10 
PE_RX3_DR5_n 10 
PE_RX2_DR5_n 10 
PE_RX2_DR5_p 10 
PE_RX3_DR5_p 10 
PE_RX4_DR5_n 10 
PE_RX4_DR5_p 10 
PE_TX3_DR4_n 10 
PE_TX3_DR4_p 10 
PE_TX4_DR4_p 10 
PE_TX4_DR4_n 10 
PE_RX3_DR4_p 10 
PE_RX3_DR4_n 10 
PE_RX4_DR4_n 10 
PE_RX4_DR4_p 10 
PE_TX2_DR3_n 9
PE_TX2_DR3_p 9
PE_TX3_DR3_n 9
PE_TX3_DR3_p 9
PE_TX1_DR3_n 9
PE_TX1_DR3_p 9
PE_TX4_DR3_p 9
PE_TX4_DR3_n 9
PE_RX4_DR3_n 9
PE_RX4_DR3_p 9
PE_RX1_DR3_n 9
PE_RX1_DR3_p 9
PE_RX2_DR3_n 9
PE_RX2_DR3_p 9
PE_RX3_DR3_p 9
PE_RX3_DR3_n 9
PE_TX2_DR7_n 11 
PE_TX2_DR7_p 11 
PE_TX3_DR7_n 11 
PE_TX3_DR7_p 11 
PE_TX1_DR7_n 11 
PE_TX1_DR7_p 11 
PE_TX4_DR7_p 11 
PE_TX4_DR7_n 11 
PE_RX1_DR7_n 11 
PE_RX2_DR7_p 11 
PE_RX2_DR7_n 11 
PE_RX1_DR7_p 11 
PE_RX3_DR7_n 11 
PE_RX3_DR7_p 11 
PE_RX4_DR7_n 11 
PE_RX4_DR7_p 11 
PE_TX2_DR2_n 9
PE_TX2_DR2_p 9
PE_TX3_DR2_n 9
PE_TX3_DR2_p 9
PE_TX1_DR2_n 9
PE_TX1_DR2_p 9
PE_TX4_DR2_p 9
PE_TX4_DR2_n 9
PE_RX4_DR2_n 9
PE_RX4_DR2_p 9
PE_RX1_DR2_n 9
PE_RX1_DR2_p 9
PE_RX2_DR2_n 9
PE_RX2_DR2_p 9
PE_RX3_DR2_p 9
PE_RX3_DR2_n 9
PE_RX4_DR11_n 13 
PE_RX4_DR11_p 13 
PE_RX1_DR11_n 13 
PE_RX1_DR11_p 13 
PE_RX2_DR11_n 13 
PE_RX2_DR11_p 13 
PE_RX3_DR11_p 13 
PE_RX3_DR11_n 13 
PE_RX4_DR6_n 11 
PE_RX4_DR6_p 11 
PE_RX1_DR6_n 11 
PE_RX1_DR6_p 11 
PE_RX2_DR6_n 11 
PE_RX2_DR6_p 11 
PE_RX3_DR6_p 11 
PE_RX3_DR6_n 11 
PE_TX2_DR11_n 13 
PE_TX2_DR11_p 13 
PE_TX3_DR11_n 13 
PE_TX3_DR11_p 13 
PE_TX1_DR11_n 13 
PE_TX1_DR11_p 13 
PE_TX4_DR11_p 13 
PE_TX4_DR11_n 13 
PE_TX2_DR6_n 11 
PE_TX2_DR6_p 11 
PE_TX3_DR6_n 11 
PE_TX3_DR6_p 11 
PE_TX1_DR6_n 11 
PE_TX1_DR6_p 11 
PE_TX4_DR6_p 11 
PE_TX4_DR6_n 11 
PWM_EXP_A 18 
SSD1_PERST_N 8
SSD0_PERST_N 8
SSD3_PERST_N 9
SSD6_PERST_N 11 
SSD7_PERST_N 11 
SSD12_PERST_N 14 
SSD11_PERST_N 13 
SSD2_PERST_N 9
SSD5_PERST_N 10 
SSD10_PERST_N 13 
SSD1_PWREN 8
SSD0_PWREN 8
SSD3_PWREN 9
SSD2_PWREN 9
SSD6_PWREN 11 
SSD11_PWREN 13 
SSD7_PWREN 11 
SSD12_PWREN 14 
SSD10_PWREN 13 
SSD5_PWREN 10 
SSD0_CLK0_OE_R_n 8,21 
SSD1_CLK0_OE_R_n 8,21 
SSD3_CLK0_OE_R_n 9,22 
SSD7_CLK0_OE_R_n 11,22 
SSD2_CLK0_OE_R_n 9,21 
SSD11_CLK0_OE_R_n 13,21 
SSD12_CLK0_OE_R_n 14,22 
SSD10_CLK0_OE_R_n 13,21 
SSD5_CLK0_OE_R_n 10,21 
ATTN_LED_DR11_N 13 
ATTN_LED_DR12_N 14 
ATTN_LED_DR10_N 13 
ATTN_LED_DR5_N 10 
PE_100M_CLK1_n 22 
PE_100M_CLK1_p 22 
PE_100M_CLK4_p 21 
PE_100M_CLK4_n 21 
PE_100M_CLK2_p 22 
PE_100M_CLK2_n 22 
PE_100M_CLK3_p 21 
PE_100M_CLK3_n 21 
Title 
Size Document Number Rev 
Date: Sheet 
of 
Lightning_PDPB 1
CARD EDGE CONN_1 
C
16 28 Thursday, March 09, 2017 
Wiwynn 
H/W R&D Dept. II 
8F,90,Sec. 1,Hsin Tai Wu Rd, 
Hsichih, Taipei Hsien 221, Taiwan, R.O.C 
Title 
Size Document Number Rev 
Date: Sheet 
of 
Lightning_PDPB 1
CARD EDGE CONN_1 
C
16 28 Thursday, March 09, 2017 
Wiwynn 
H/W R&D Dept. II 
8F,90,Sec. 1,Hsin Tai Wu Rd, 
Hsichih, Taipei Hsien 221, Taiwan, R.O.C 
Title 
Size Document Number Rev 
Date: Sheet 
of 
Lightning_PDPB 1
CARD EDGE CONN_1 
C
16 28 Thursday, March 09, 2017 
Wiwynn 
H/W R&D Dept. II 
8F,90,Sec. 1,Hsin Tai Wu Rd, 
Hsichih, Taipei Hsien 221, Taiwan, R.O.C 
C9539 SCD01U50V2KX-1GP 12
PC1169 
SCD01U50V2KX-1GP 
1 2
R9036 
0R2J-2-GP 
1 2
PC1164 
SCD1U50V3KX-GP 
1 2
TOP BOTTOM 
J18 
PCISLT200-5-GP-U 
G#A1 A1 
S#A2 A2 
S#A3 A3 
G#A4 A4 
S#A5 A5 
S#A6 A6 
G#A7 A7 
S#A8 A8 
S#A9 A9 
G#A10 A10 
S#A11 A11 
S#A12 A12 
G#A13 A13 
S#A14 A14 
S#A15 A15 
G#A16 A16 
S#A17 A17 
S#A18 A18 
G#A19 A19 
S#A20 A20 
S#A21 A21 
G#A22 A22 
S#A23 A23 
S#A24 A24 
G#A25 A25 
S#A26 A26 
S#A27 A27 
G#A28 A28 
S#A29 A29 
S#A30 A30 
G#A31 A31 
S#A32 A32 
S#A33 A33 
G#A34 A34 
S#A35 A35 
S#A36 A36 
G#A37 A37 
S#A38 A38 
S#A39 A39 
G#A40 A40 
S#A41 A41 
S#A42 A42 
G#A43 A43 
R#A44 A44 
G#A45 A45 
S#A46 A46 
S#A47 A47 
G#A48 A48 
S#A49 A49 
S#A50 A50 
G#A51 A51 
S#A52 A52 
S#A53 A53 
G#A54 A54 
S#A55 A55 
S#A56 A56 
G#A57 A57 
S#A58 A58 
S#A59 A59 
G#A60 A60 
S#A61 A61 
S#A62 A62 
G#A63 A63 
S#A64 A64 
S#A65 A65 
G#A66 A66 
S#A67 A67 
S#A68 A68 
G#A69 A69 
S#A70 A70 
S#A71 A71 
G#A72 A72 
S#A73 A73 
S#A74 A74 
G#A75 A75 
S#A76 A76 
S#A77 A77 
G#A78 A78 
S#A79 A79 
S#A80 A80 
G#A81 A81 
S#A82 A82 
S#A83 A83 
G#A84 A84 
S#A85 A85 
S#A86 A86 
G#A87 A87 
S#A88 A88 
S#A89 A89 
G#A90 A90 
S#A91 A91 
S#A92 A92 
G#A93 A93 
S#A94 A94 
S#A95 A95 
G#A96 A96 
S#A97 A97 
S#A98 A98 
G#A99 A99 
R#A100 A100 
R#B1 B1 
G#B2 B2 
S#B3 B3 
S#B4 B4 
G#B5 B5 
S#B6 B6 
S#B7 B7 
G#B8 B8 
S#B9 B9 
S#B10 B10 
G#B11 B11 
S#B12 B12 
S#B13 B13 
G#B14 B14 
S#B15 B15 
S#B16 B16 
G#B17 B17 
S#B18 B18 
S#B19 B19 
G#B20 B20 
S#B21 B21 
S#B22 B22 
G#B23 B23 
S#B24 B24 
S#B25 B25 
G#B26 B26 
S#B27 B27 
S#B28 B28 
G#B29 B29 
S#B30 B30 
S#B31 B31 
G#B32 B32 
S#B33 B33 
S#B34 B34 
G#B35 B35 
S#B36 B36 
S#B37 B37 
G#B38 B38 
S#B39 B39 
S#B40 B40 
G#B41 B41 
S#B42 B42 
S#B43 B43 
G#B44 B44 
R#B45 B45 
G#B46 B46 
S#B47 B47 
S#B48 B48 
G#B49 B49 
S#B50 B50 
S#B51 B51 
G#B52 B52 
S#B53 B53 
S#B54 B54 
G#B55 B55 
S#B56 B56 
S#B57 B57 
G#B58 B58 
S#B59 B59 
S#B60 B60 
G#B61 B61 
S#B62 B62 
S#B63 B63 
G#B64 B64 
S#B65 B65 
S#B66 B66 
G#B67 B67 
S#B68 B68 
S#B69 B69 
G#B70 B70 
S#B71 B71 
S#B72 B72 
G#B73 B73 
S#B74 B74 
S#B75 B75 
G#B76 B76 
S#B77 B77 
S#B78 B78 
G#B79 B79 
S#B80 B80 
S#B81 B81 
G#B82 B82 
S#B83 B83 
S#B84 B84 
G#B85 B85 
S#B86 B86 
S#B87 B87 
G#B88 B88 
S#B89 B89 
S#B90 B90 
G#B91 B91 
S#B92 B92 
S#B93 B93 
G#B94 B94 
S#B95 B95 
S#B96 B96 
G#B97 B97 
S#B98 B98 
S#B99 B99 
G#B100 B100 
NP1 NP1 NP2 NP2 
R411 
100R2J-2-GP 
1 2
PC1168 
SC22U25V6KX-GP-U 
1 2
C9540 SCD01U50V2KX-1GP 1 2
C9536 SCD01U50V2KX-1GP 12
C9541 SCD01U50V2KX-1GP 1 2
C9537 SCD01U50V2KX-1GP 12
C9534 SCD01U50V2KX-1GP 1 2
C9535 SCD01U50V2KX-1GP 1 2
TOP BOTTOM 
J17 
PCISLT200-5-GP-U 
G#A1 A1 
S#A2 A2 
S#A3 A3 
G#A4 A4 
S#A5 A5 
S#A6 A6 
G#A7 A7 
S#A8 A8 
S#A9 A9 
G#A10 A10 
S#A11 A11 
S#A12 A12 
G#A13 A13 
S#A14 A14 
S#A15 A15 
G#A16 A16 
S#A17 A17 
S#A18 A18 
G#A19 A19 
S#A20 A20 
S#A21 A21 
G#A22 A22 
S#A23 A23 
S#A24 A24 
G#A25 A25 
S#A26 A26 
S#A27 A27 
G#A28 A28 
S#A29 A29 
S#A30 A30 
G#A31 A31 
S#A32 A32 
S#A33 A33 
G#A34 A34 
S#A35 A35 
S#A36 A36 
G#A37 A37 
S#A38 A38 
S#A39 A39 
G#A40 A40 
S#A41 A41 
S#A42 A42 
G#A43 A43 
R#A44 A44 
G#A45 A45 
S#A46 A46 
S#A47 A47 
G#A48 A48 
S#A49 A49 
S#A50 A50 
G#A51 A51 
S#A52 A52 
S#A53 A53 
G#A54 A54 
S#A55 A55 
S#A56 A56 
G#A57 A57 
S#A58 A58 
S#A59 A59 
G#A60 A60 
S#A61 A61 
S#A62 A62 
G#A63 A63 
S#A64 A64 
S#A65 A65 
G#A66 A66 
S#A67 A67 
S#A68 A68 
G#A69 A69 
S#A70 A70 
S#A71 A71 
G#A72 A72 
S#A73 A73 
S#A74 A74 
G#A75 A75 
S#A76 A76 
S#A77 A77 
G#A78 A78 
S#A79 A79 
S#A80 A80 
G#A81 A81 
S#A82 A82 
S#A83 A83 
G#A84 A84 
S#A85 A85 
S#A86 A86 
G#A87 A87 
S#A88 A88 
S#A89 A89 
G#A90 A90 
S#A91 A91 
S#A92 A92 
G#A93 A93 
S#A94 A94 
S#A95 A95 
G#A96 A96 
S#A97 A97 
S#A98 A98 
G#A99 A99 
R#A100 A100 
R#B1 B1 
G#B2 B2 
S#B3 B3 
S#B4 B4 
G#B5 B5 
S#B6 B6 
S#B7 B7 
G#B8 B8 
S#B9 B9 
S#B10 B10 
G#B11 B11 
S#B12 B12 
S#B13 B13 
G#B14 B14 
S#B15 B15 
S#B16 B16 
G#B17 B17 
S#B18 B18 
S#B19 B19 
G#B20 B20 
S#B21 B21 
S#B22 B22 
G#B23 B23 
S#B24 B24 
S#B25 B25 
G#B26 B26 
S#B27 B27 
S#B28 B28 
G#B29 B29 
S#B30 B30 
S#B31 B31 
G#B32 B32 
S#B33 B33 
S#B34 B34 
G#B35 B35 
S#B36 B36 
S#B37 B37 
G#B38 B38 
S#B39 B39 
S#B40 B40 
G#B41 B41 
S#B42 B42 
S#B43 B43 
G#B44 B44 
R#B45 B45 
G#B46 B46 
S#B47 B47 
S#B48 B48 
G#B49 B49 
S#B50 B50 
S#B51 B51 
G#B52 B52 
S#B53 B53 
S#B54 B54 
G#B55 B55 
S#B56 B56 
S#B57 B57 
G#B58 B58 
S#B59 B59 
S#B60 B60 
G#B61 B61 
S#B62 B62 
S#B63 B63 
G#B64 B64 
S#B65 B65 
S#B66 B66 
G#B67 B67 
S#B68 B68 
S#B69 B69 
G#B70 B70 
S#B71 B71 
S#B72 B72 
G#B73 B73 
S#B74 B74 
S#B75 B75 
G#B76 B76 
S#B77 B77 
S#B78 B78 
G#B79 B79 
S#B80 B80 
S#B81 B81 
G#B82 B82 
S#B83 B83 
S#B84 B84 
G#B85 B85 
S#B86 B86 
S#B87 B87 
G#B88 B88 
S#B89 B89 
S#B90 B90 
G#B91 B91 
S#B92 B92 
S#B93 B93 
G#B94 B94 
S#B95 B95 
S#B96 B96 
G#B97 B97 
S#B98 B98 
S#B99 B99 
G#B100 B100 
NP1 NP1 NP2 NP2 
PC1165 
SCD01U50V2KX-1GP 
1 2
R406 
10KR2F-2-GP 
NOPOP 
1 2
R579 
2R2010J-1-GP 
12
PC1167 
SC22U25V6KX-GP-U 
1 2
PC1163 
SCD1U50V3KX-GP 
1 2
PC1096 
SC22U25V6KX-GP-U 
1 2
PC1166 
SC22U25V6KX-GP-U 
1 2
C9538 SCD01U50V2KX-1GP 12



5
5
4
4
3
3
2
2
1
1
D D
C C
B B
A A
1:not mated 
0:Mated 
CARD EDGE CONN3 
TRAY_ID_R 
SD_LATCH_RELEASE_R 
PCIE_MATED#_B 
SSD14_CLK0_OE_R_n 15,22 
SSD9_CLK0_OE_R_n 12,22 
SSD13_CLK0_OE_R_n 14,22 
ATTN_LED_DR9_N 12 
ATTN_LED_DR13_N 14 
TRAY_ID 18 
I2C_MUX_RESET_PEB 19 
SD_LATCH_RELEASE 18 
PE_TX2_DR4_p 10 
PE_TX2_DR4_n 10 
PE_TX1_DR4_n 10 
PE_TX1_DR4_p 10 
PE_TX2_DR8_p 12 
PE_TX2_DR8_n 12 
PE_TX1_DR8_n 12 
PE_TX3_DR8_p 12 
PE_TX3_DR8_n 12 
PE_TX4_DR8_p 12 
PE_TX1_DR8_p 12 
PE_TX4_DR8_n 12 
PE_TX2_DR12_p 14 
PE_TX2_DR12_n 14 
PE_TX1_DR12_n 14 
PE_TX3_DR12_p 14 
PE_TX3_DR12_n 14 
PE_TX4_DR12_p 14 
PE_TX1_DR12_p 14 
PE_TX4_DR12_n 14 
PE_TX1_DR9_n 12 
PE_TX2_DR9_n 12 
PE_TX2_DR9_p 12 
PE_TX1_DR9_p 12 
PE_TX4_DR9_p 12 
PE_TX3_DR9_n 12 
PE_TX3_DR9_p 12 
PE_TX4_DR9_n 12 
PE_TX2_DR13_p 14 
PE_TX2_DR13_n 14 
PE_TX1_DR13_n 14 
PE_TX3_DR13_p 14 
PE_TX3_DR13_n 14 
PE_TX4_DR13_p 14 
PE_TX1_DR13_p 14 
PE_TX4_DR13_n 14 
PE_TX2_DR14_n 15 
PE_TX2_DR14_p 15 
PE_TX3_DR14_n 15 
PE_TX3_DR14_p 15 
PE_TX1_DR14_n 15 
PE_TX1_DR14_p 15 
PE_TX4_DR14_p 15 
PE_TX4_DR14_n 15 
PE_RX1_DR4_n 10 
PE_RX1_DR4_p 10 
PE_RX2_DR4_n 10 
PE_RX2_DR4_p 10 
PE_RX4_DR8_n 12 
PE_RX4_DR8_p 12 
PE_RX1_DR8_n 12 
PE_RX1_DR8_p 12 
PE_RX2_DR8_n 12 
PE_RX2_DR8_p 12 
PE_RX3_DR8_p 12 
PE_RX3_DR8_n 12 
PE_RX4_DR12_n 14 
PE_RX4_DR12_p 14 
PE_RX1_DR12_n 14 
PE_RX1_DR12_p 14 
PE_RX2_DR12_n 14 
PE_RX2_DR12_p 14 
PE_RX3_DR12_p 14 
PE_RX3_DR12_n 14 
PE_RX4_DR9_n 12 
PE_RX4_DR9_p 12 
PE_RX3_DR9_p 12 
PE_RX3_DR9_n 12 
PE_RX4_DR13_n 14 
PE_RX4_DR13_p 14 
PE_RX1_DR13_n 14 
PE_RX1_DR13_p 14 
PE_RX2_DR13_n 14 
PE_RX2_DR13_p 14 
PE_RX3_DR13_p 14 
PE_RX3_DR13_n 14 
PE_RX1_DR9_n 12 
PE_RX1_DR9_p 12 
PE_RX2_DR9_n 12 
PE_RX2_DR9_p 12 
PE_RX4_DR14_n 15 
PE_RX4_DR14_p 15 
PE_RX1_DR14_n 15 
PE_RX1_DR14_p 15 
PE_RX2_DR14_n 15 
PE_RX2_DR14_p 15 
PE_RX3_DR14_p 15 
PE_RX3_DR14_n 15 
SSD9_PERST_N 12 
SSD13_PERST_N 14 
SSD8_PERST_N 12 
SSD14_PERST_N 15 
SSD4_PERST_N 10 
SSD9_PWREN 12 
SSD13_PWREN 14 
SSD8_PWREN 12 
SSD4_PWREN 10 
SSD14_PWREN 15 
SSD8_CLK0_OE_R_n 12,22 
SSD4_CLK0_OE_R_n 10,22 
ATTN_LED_DR8_N 12 
ATTN_LED_DR4_N 10 
ATTN_LED_DR14_N 15 
Title 
Size Document Number Rev
Date: Sheet 
of 
Lightning_PDPB 1
CARD EDGE CONN_2 
A3 
17 28Thursday, March 02, 2017 
Wiwynn 
H/W R&D Dept. II 
8F,90,Sec. 1,Hsin Tai Wu Rd, 
Hsichih, Taipei Hsien 221, Taiwan, R.O.C
Title 
Size Document Number Rev
Date: Sheet 
of 
Lightning_PDPB 1
CARD EDGE CONN_2 
A3 
17 28Thursday, March 02, 2017 
Wiwynn 
H/W R&D Dept. II 
8F,90,Sec. 1,Hsin Tai Wu Rd, 
Hsichih, Taipei Hsien 221, Taiwan, R.O.C
Title 
Size Document Number Rev
Date: Sheet 
of 
Lightning_PDPB 1
CARD EDGE CONN_2 
A3 
17 28Thursday, March 02, 2017 
Wiwynn 
H/W R&D Dept. II 
8F,90,Sec. 1,Hsin Tai Wu Rd, 
Hsichih, Taipei Hsien 221, Taiwan, R.O.C
TOP BOTTOM 
J19 
PCISLT200-5-GP-U 
G#A1 A1 
S#A2 A2 
S#A3 A3 
G#A4 A4 
S#A5 A5 
S#A6 A6 
G#A7 A7 
S#A8 A8 
S#A9 A9 
G#A10 A10 
S#A11 A11 
S#A12 A12 
G#A13 A13 
S#A14 A14 
S#A15 A15 
G#A16 A16 
S#A17 A17 
S#A18 A18 
G#A19 A19 
S#A20 A20 
S#A21 A21 
G#A22 A22 
S#A23 A23 
S#A24 A24 
G#A25 A25 
S#A26 A26 
S#A27 A27 
G#A28 A28 
S#A29 A29 
S#A30 A30 
G#A31 A31 
S#A32 A32 
S#A33 A33 
G#A34 A34 
S#A35 A35 
S#A36 A36 
G#A37 A37 
S#A38 A38 
S#A39 A39 
G#A40 A40 
S#A41 A41 
S#A42 A42 
G#A43 A43 
R#A44 A44 
G#A45 A45 
S#A46 A46 
S#A47 A47 
G#A48 A48 
S#A49 A49 
S#A50 A50 
G#A51 A51 
S#A52 A52 
S#A53 A53 
G#A54 A54 
S#A55 A55 
S#A56 A56 
G#A57 A57 
S#A58 A58 
S#A59 A59 
G#A60 A60 
S#A61 A61 
S#A62 A62 
G#A63 A63 
S#A64 A64 
S#A65 A65 
G#A66 A66 
S#A67 A67 
S#A68 A68 
G#A69 A69 
S#A70 A70 
S#A71 A71 
G#A72 A72 
S#A73 A73 
S#A74 A74 
G#A75 A75 
S#A76 A76 
S#A77 A77 
G#A78 A78 
S#A79 A79 
S#A80 A80 
G#A81 A81 
S#A82 A82 
S#A83 A83 
G#A84 A84 
S#A85 A85 
S#A86 A86 
G#A87 A87 
S#A88 A88 
S#A89 A89 
G#A90 A90 
S#A91 A91 
S#A92 A92 
G#A93 A93 
S#A94 A94 
S#A95 A95 
G#A96 A96 
S#A97 A97 
S#A98 A98 
G#A99 A99 
R#A100 A100 
R#B1 B1 
G#B2 B2 
S#B3 B3 
S#B4 B4 
G#B5 B5 
S#B6 B6 
S#B7 B7 
G#B8 B8 
S#B9 B9 
S#B10 B10 
G#B11 B11 
S#B12 B12 
S#B13 B13 
G#B14 B14 
S#B15 B15 
S#B16 B16 
G#B17 B17 
S#B18 B18 
S#B19 B19 
G#B20 B20 
S#B21 B21 
S#B22 B22 
G#B23 B23 
S#B24 B24 
S#B25 B25 
G#B26 B26 
S#B27 B27 
S#B28 B28 
G#B29 B29 
S#B30 B30 
S#B31 B31 
G#B32 B32 
S#B33 B33 
S#B34 B34 
G#B35 B35 
S#B36 B36 
S#B37 B37 
G#B38 B38 
S#B39 B39 
S#B40 B40 
G#B41 B41 
S#B42 B42 
S#B43 B43 
G#B44 B44 
R#B45 B45 
G#B46 B46 
S#B47 B47 
S#B48 B48 
G#B49 B49 
S#B50 B50 
S#B51 B51 
G#B52 B52 
S#B53 B53 
S#B54 B54 
G#B55 B55 
S#B56 B56 
S#B57 B57 
G#B58 B58 
S#B59 B59 
S#B60 B60 
G#B61 B61 
S#B62 B62 
S#B63 B63 
G#B64 B64 
S#B65 B65 
S#B66 B66 
G#B67 B67 
S#B68 B68 
S#B69 B69 
G#B70 B70 
S#B71 B71 
S#B72 B72 
G#B73 B73 
S#B74 B74 
S#B75 B75 
G#B76 B76 
S#B77 B77 
S#B78 B78 
G#B79 B79 
S#B80 B80 
S#B81 B81 
G#B82 B82 
S#B83 B83 
S#B84 B84 
G#B85 B85 
S#B86 B86 
S#B87 B87 
G#B88 B88 
S#B89 B89 
S#B90 B90 
G#B91 B91 
S#B92 B92 
S#B93 B93 
G#B94 B94 
S#B95 B95 
S#B96 B96 
G#B97 B97 
S#B98 B98 
S#B99 B99 
G#B100 B100 
NP1 NP1 NP2 NP2 
R9038 0R2J-2-GP 12
R584 
2R2010J-1-GP 
1 2
R9035 0R2J-2-GP 12



5
5
4
4
3
3
2
2
1
1
D D
C C
B B
A A
STRADDLE CONN 
Close to 
Connect 
Close to 
Connect 
Close to 
Connect 
22U 
1206 
X6S 
22U 
1206 
X6S 
P12V 
P12V 
P3V3 
SELF_1A&2A_HB 16 
FCB_HW_REVISION 16 
TRAY_ID 17 
I2C_C_SCL 19 
I2C_C_SDA 19 
PEER_TRAY_PRESENT 16 
SELF_TRAY_PRESENT 16 
SD_LATCH_RELEASE 17 
PEER_1A&2A_HB 16 
PWM_EXP_A 16 
Title 
Size Document Number Rev
Date: Sheet 
of 
Lightning_PDPB 1
STRADDLE CONN 
A3 
18 28Thursday, March 02, 2017 
Wiwynn 
H/W R&D Dept. II 
8F,90,Sec. 1,Hsin Tai Wu Rd, 
Hsichih, Taipei Hsien 221, Taiwan, R.O.C
Title 
Size Document Number Rev
Date: Sheet 
of 
Lightning_PDPB 1
STRADDLE CONN 
A3 
18 28Thursday, March 02, 2017 
Wiwynn 
H/W R&D Dept. II 
8F,90,Sec. 1,Hsin Tai Wu Rd, 
Hsichih, Taipei Hsien 221, Taiwan, R.O.C
Title 
Size Document Number Rev
Date: Sheet 
of 
Lightning_PDPB 1
STRADDLE CONN 
A3 
18 28Thursday, March 02, 2017 
Wiwynn 
H/W R&D Dept. II 
8F,90,Sec. 1,Hsin Tai Wu Rd, 
Hsichih, Taipei Hsien 221, Taiwan, R.O.C
C9533 
SCD01U50V2KX-1GP 
1 2 C348 
SC22U25V6KX-GP-U 
1 2
C355 
SC220P50V3JN-GP 
NOPOP 
1 2
C349 
SC22U25V6KX-GP-U 
1 2
PC1290 
SC10U25V6KX-4GP 
1 2
C356 
SC220P50V3JN-GP 
NOPOP 
1 2
TOP BOTTOM 
02 Do not mirror 
CN7 
AMP-CONN60-5-GP 
P1 
P2 
P3 
P4 
P5 
P6 
P7 
P8 
P9 
P10 
P11 
P12 
P13 
P14 
P15 
P16 
P17 
P18 P19 
P20 
P21 
P22 
P23 
P24 
P25 
P26 
P27 
P28 
P29 
P30 
P31 
P32 
P33 
P34 
P35 
P36 
S1 
S2 
S3 
S4 
S5 
S6 
S7 
S8 
S9 
S10 
S11 
S13 
S14 
S15 
S16 
S17 
S18 
S19 
S20 
S21 
S22 
S23 
S24 
NP1 
NP2 
S12 
PC1291 
SCD1U25V3KX-GP 
1 2
TP1 
TPAD28-2-GP 
1
PC1289 
SCD1U25V3KX-GP 
1 2
TP2 
TPAD28-2-GP 
1
TP3 
TPAD28-2-GP 
1



5
5
4
4
3
3
2
2
1
1
D D
C C
B B
A A
EEPROM 
I2C_B_TMP3 0X94 I2C_B_TMP2 0X92 
I2C_B_TMP4 0X96 
ADDR=1010001 (0XA2) 
Input Cap: 10pF 
Operating current: 5mA 
ADDR=1001000 (0x90) 
VOLTAGE SENSOR 
Operating current: 300uA 
I2C_B_Pull-High I2C_8_Pull-High 
Isolation Switch on PEB 
SPARE I2C 
I2C_B for Temp Sensors,EEPROM 
I2C_B_TMP1 0X98 
I2C_9_Pull-High I2C_C_Pull-High 
I2C_C for PTB 
Input Cap: 3pF 
Operating current: 100 uA 
Input Cap: 3pF 
Operating current: 100 uA 
Input Cap: 3pF 
Operating current: 100 uA 
Input Cap: 3pF 
Operating current: 100 uA 
I2C_DEVICE 
1U 
0402 
X6S 
1U 
0402 
X6S 
0.1U 
0402 
X7R 
0.1U 
0402 
X7R 
1U 
0603 
X7R 
1U 
0603 
X7R 
1U 
0402 
X7R 
1U 
0402 
X7R 
1U 
0402 
X7R 
1U 
0402 
X7R 
Input Cap: 10pF 
0.1U 
0402 
X7R 
I2C_B_TMP3_A0 
I2C_B_TMP3_A1 
I2C_B_TMP3_A2 
I2C_B_TMP2_A0 
I2C_B_TMP2_A1 
I2C_B_TMP2_A2 
I2C_B_TMP4_A0 
I2C_B_TMP4_A1 
I2C_B_TMP4_A2 
I2C_B_TMP3_ALERT 
I2C_B_TMP2_ALERT 
EEPROM_A0 
EEPROM_A1 
EEPROM_A2 
EEPROM_WP 
I2C_B_TMP4_ALERT 
EEPROM_SCL I2C_B_SCL 
EEPROM_SDA I2C_B_SDA 
TMP3_SCL 
TMP3_SDA 
TMP2_SDA 
TMP2_SCL 
TMP4_SCL 
TMP4_SDA 
I2C_B_SCL 
I2C_B_SDA 
VOL_SEN_ADDR 
VOL_SEN_ALERT 
VOL_SEN_SCL 
VOL_SEN_SDA 
I2C_B_SCL 
I2C_B_SDA 
I2C_B_SDA 
I2C_B_SCL 
I2C_B_TMP1_ALERT 
TMP1_SDA 
I2C_B_TMP1_A1 
I2C_B_TMP1_A0 
I2C_B_TMP1_A2 
TMP1_SCL 
I2C_B_SCL 
I2C_B_SDA 
I2C_B_SDA 
I2C_B_SCL 
I2C_B_SDA 
I2C_B_SCL 
I2C_B_SDA 
I2C_B_SCL 
P12V_SENSE 
P12V_SSD14_SENSE 
P3V3_SENSE 
P3V3 
P3V3 
P3V3 
P3V3 
P3V3 P3V3 
P3V3 
P3V3 
P3V3 
P3V3 
P3V3 
P3V3 P3V3 P3V3 
P3V3 P3V3 
P3V3 
P12V P12V_SSD14 P3V3 
I2C_MUX_RESET_PEB 17 
BMC_I2C_SDA_BUF_8 16,20,22 BMC_I2C_SDA_BUF_9 16,20,21 
BMC_I2C_SCL_BUF_8 16,20,22 BMC_I2C_SCL_BUF_9 16,20,21 
I2C_MUX_RESET 20 
SAS_I2C_C_BUF_SDA_R 16 
SAS_I2C_C_BUF_SCL_R 16 
I2C_C_SDA 18,19 
I2C_C_SCL 18,19 
SAS_I2C_B_BUF_SCL_R 16 
SAS_I2C_B_BUF_SDA_R 16 
I2C_C_SCL 18,19 
I2C_C_SDA 18,19 
Title 
Size Document Number Rev 
Date: Sheet 
of 
Lightning_PDPB 1
I2C_DEVICES 
C
19 28 Thursday, March 02, 2017 
Wiwynn 
H/W R&D Dept. II 
8F,90,Sec. 1,Hsin Tai Wu Rd, 
Hsichih, Taipei Hsien 221, Taiwan, R.O.C 
Title 
Size Document Number Rev 
Date: Sheet 
of 
Lightning_PDPB 1
I2C_DEVICES 
C
19 28 Thursday, March 02, 2017 
Wiwynn 
H/W R&D Dept. II 
8F,90,Sec. 1,Hsin Tai Wu Rd, 
Hsichih, Taipei Hsien 221, Taiwan, R.O.C 
Title 
Size Document Number Rev 
Date: Sheet 
of 
Lightning_PDPB 1
I2C_DEVICES 
C
19 28 Thursday, March 02, 2017 
Wiwynn 
H/W R&D Dept. II 
8F,90,Sec. 1,Hsin Tai Wu Rd, 
Hsichih, Taipei Hsien 221, Taiwan, R.O.C 
R326 
0R2J-2-GP 
1 2
U49 
TMP75AIDGKR-GP 
SDA 1
SCL 2
ALERT 3
GND 4 A2 5A1 6A0 7V+ 8
R341 
4K7R2F-GP 
NOPOP 1 2
R353 
4K7R2F-GP 
1 2
R367 
4K7R2J-2-GP 
NOPOP 
1 2
R390 
2KR2F-3-GP 
1 2
C357 
SCD1U16V2KX-3GP 
1 2
R318 
4K7R2F-GP 
NOPOP 1 2
R371 
4K7R2J-2-GP 
NOPOP 
1 2
R368 
4K7R2J-2-GP 
NOPOP 
1 2
PR9059 0R2J-2-GP 1 2
R334 
0R2J-2-GP 
1 2
R343 
4K7R2J-2-GP 
NOPOP 1 2
R388 
10KR2F-2-GP 
1 2
R387 
10KR2F-2-GP 
1 2
R342 
4K7R2F-GP 
1 2
R339 
4K7R2J-2-GP 
1 2
C346 
SC1U16V3KX-5GP 
1 2
C343 
SCD1U16V2KX-3GP 
1 2
R372 
4K7R2J-2-GP 
NOPOP 
1 2
TP4 
TPAD32-GP 
1
R352 0R2J-2-GP 1 2
R329 
4K7R2J-2-GP 
1 2
R364 
4K7R2F-GP 
NOPOP 
1 2
TP150 
TPAD32-GP 
1
R9757 
0R2J-2-GP 
1 2
TP6 
TPAD32-GP 
1
PR9060 0R2J-2-GP 1 2
C344 
SCD1U16V2KX-3GP 
1 2
R314 
0R2J-2-GP 
1 2
R317 
4K7R2J-2-GP 
1 2
U50 
24LC64T-I-GP 
A1 2
A2 3
A0 1
SDA 5VSS 4 SCL 6WP 7VCC 8
TP7 
TPAD32-GP 
1
R316 
4K7R2F-GP 
NOPOP 1 2
PR9065 0R2J-2-GP 1 2
R325 
4K7R2J-2-GP 
NOPOP 1 2
R9758 
1KR2J-1-GP 
NOPOP 
1 2
R319 
0R2J-2-GP 
1 2
R379 0R2J-2-GP 1 2
R328 
4K7R2F-GP 
NOPOP 
1 2
U51 
TMP75AIDGKR-GP 
SDA 1
SCL 2
ALERT 3
GND 4 A2 5A1 6A0 7V+ 8
PR9057 0R2J-2-GP 1 2
R331 
4K7R2F-GP 
NOPOP 1 2
R333 
4K7R2J-2-GP 
1 2
R338 
4K7R2J-2-GP 
1 2
R351 0R2J-2-GP 1 2
PR9058 0R2J-2-GP 1 2
R381 
4K7R2J-2-GP 
1 2
R346 
4K7R2F-GP 
NOPOP 1 2
C347 
SCD1U50V3KX-GP 
1 2
U47 
TMP75AIDGKR-GP 
SDA 1
SCL 2
ALERT 3
GND 4 A2 5A1 6A0 7V+ 8
R320 
0R2J-2-GP 
1 2
R340 
4K7R2F-GP 
NOPOP 1 2
C341 
SCD1U16V2KX-3GP 
1 2
C358 
SCD1U16V2KX-3GP 
1 2
R327 
4K7R2F-GP 
NOPOP 
1 2
R354 0R2J-2-GP 1 2
R323 
4K7R2J-2-GP 
1 2
U48 
TMP75AIDGKR-GP 
SDA 1
SCL 2
ALERT 3
GND 4 A2 5A1 6A0 7V+ 8
R374 
4K7R2J-2-GP 
NOPOP 
1 2
R321 
0R2J-2-GP 
1 2
R336 
4K7R2J-2-GP 
1 2
R369 
4K7R2J-2-GP 
NOPOP 
1 2
R389 
2KR2F-3-GP 
1 2
R345 
4K7R2J-2-GP 
1 2
C352 
SCD1U16V2KX-3GP 
1 2
R330 
0R2J-2-GP 
1 2
TP5 
TPAD32-GP 
1
R375 
4K7R2J-2-GP 
NOPOP 
1 2
R348 
4K7R2F-GP 
NOPOP 1 2
R337 
4K7R2F-GP 
NOPOP 
1 2
R335 
0R2J-2-GP 
1 2
R362 
4K7R2F-GP 
NOPOP 
1 2
R349 
4K7R2J-2-GP 
1 2
C363 
SC1U10V2KX-7-GP 
1 2
R382 0R2J-2-GP 1 2
U53 
ADS1015IDGSR-GP 
ADDR 1
ALERT/RDY 2
GND 3
AIN0 4
AIN1 5
AIN2 6
AIN3 7
VDD 8
SDA 9SCL 10 
R350 
4K7R2J-2-GP 
1 2
R370 
4K7R2J-2-GP 
NOPOP 
1 2
C359 
SCD1U16V2KX-3GP 
1 2
R324 
4K7R2F-GP 
1 2
R315 
4K7R2F-GP 
NOPOP 1 2
R347 
4K7R2F-GP 
NOPOP 1 2
R344 
4K7R2J-2-GP 
1 2
C342 
SCD1U16V2KX-3GP 
1 2
R322 
4K7R2J-2-GP 
NOPOP 1 2
R332 
4K7R2J-2-GP 
1 2



5
5
4
4
3
3
2
2
1
1
D D
C C
B B
A A
I2C Adress:1110 0010(0xE2) 
I2C Adress:1110 0100(0xE4) 
I2C_BUS_SWITCH1-2 
Input Cap: 19pF 
Input Cap: 19pF 
I2C_SW_EU16_ADDRESS_A1 
I2C_SW_EU16_ADDRESS_A2 
I2C_SW_EU16_ADDRESS_A0 
I2C_MUX_RESET_R_EU16 
I2C_SW_EU17_ADDRESS_A2 
I2C_MUX_RESET_R_EU17 
I2C_SW_EU17_ADDRESS_A1 
I2C_SW_EU17_ADDRESS_A0 
I2C8_SCL_R_SW_EU16 
I2C8_SDA_R_SW_EU16 
I2C8_SCL_R_SW_EU17 
I2C8_SDA_R_SW_EU17 
P3V3 
P3V3 
P3V3 
P3V3 
P3V3 
P3V3 
SDA_DR3 9
SCL_DR4 10 
SCL_DR3 9
SCL_DR12 14 
SCL_DR13 14 
SCL_DR8 12 
SCL_DR14 15 
SCL_DR9 12 
SDA_DR4 10 
SDA_DR12 14 
SDA_DR8 12 
SDA_DR13 14 
SDA_DR9 12 
SDA_DR14 15 
SDA_DR2 9
SCL_DR1 8
SCL_DR2 9
SCL_DR5 10 
SCL_DR0 8
SCL_DR6 11 
SCL_DR10 13 
SCL_DR11 13 
SDA_DR1 8
SDA_DR0 8
SDA_DR5 10 
SDA_DR10 13 
SDA_DR6 11 
SDA_DR11 13 
BMC_I2C_SDA_BUF_8 16,19,22 
BMC_I2C_SCL_BUF_8 16,19,22 
I2C_MUX_RESET 19,20 
I2C_MUX_RESET 19,20 
BMC_I2C_SDA_BUF_9 16,19,21 
BMC_I2C_SCL_BUF_9 16,19,21 
SCL_DR7 11 
SDA_DR7 11 
Title 
Size Document Number Rev
Date: Sheet 
of 
Lightning_PDPB 1
I2C_BUS_SWITCH 
A3 
20 28Thursday, March 09, 2017 
Wiwynn 
H/W R&D Dept. II 
8F,90,Sec. 1,Hsin Tai Wu Rd, 
Hsichih, Taipei Hsien 221, Taiwan, R.O.C
Title 
Size Document Number Rev
Date: Sheet 
of 
Lightning_PDPB 1
I2C_BUS_SWITCH 
A3 
20 28Thursday, March 09, 2017 
Wiwynn 
H/W R&D Dept. II 
8F,90,Sec. 1,Hsin Tai Wu Rd, 
Hsichih, Taipei Hsien 221, Taiwan, R.O.C
Title 
Size Document Number Rev
Date: Sheet 
of 
Lightning_PDPB 1
I2C_BUS_SWITCH 
A3 
20 28Thursday, March 09, 2017 
Wiwynn 
H/W R&D Dept. II 
8F,90,Sec. 1,Hsin Tai Wu Rd, 
Hsichih, Taipei Hsien 221, Taiwan, R.O.C
SR986 
4K7R2J-2-GP 
1 2
SR972 
4K7R2J-2-GP 
1 2
SR987 
4K7R2J-2-GP 
1 2
PR9047 
0R2J-2-GP 
1 2
EU17 
PCA9547BS-GP 
VSS 9
A2 18 
VDD 21 
A0 22 
A1 23 
GND 25 
SC0 2
SC1 4
SC2 6
SC3 8
SC4 11 
SC5 13 
SC6 15 
SC7 17 
SD0 1
SD1 3
SD2 5
SD3 7
SD4 10 
SD5 12 
SD6 14 
SD7 16 
SCL 19 
SDA 20 
RESET# 24 
SR1153 
4K7R2F-GP 
NOPOP 1 2
SR967 
4K7R2J-2-GP 
1 2
SR982 
4K7R2J-2-GP 
1 2
R430 0R2J-2-GP 1 2
R428 0R2J-2-GP 1 2
SR965 
4K7R2J-2-GP 
1 2
SR984 
4K7R2J-2-GP 
1 2
SR993 
4K7R2J-2-GP 
1 2
SR1155 
4K7R2F-GP 
NOPOP 1 2
SR976 
4K7R2J-2-GP 
1 2
SR979 
4K7R2J-2-GP 
1 2
R427 0R2J-2-GP 1 2
C9322 
SCD1U25V3KX-GP 
1 2
SR991 
4K7R2J-2-GP 
1 2
SR1046 
4K7R2F-GP 
1 2
SR974 
4K7R2J-2-GP 
1 2
SR980 
4K7R2J-2-GP 
1 2
SR989 
4K7R2J-2-GP 
1 2
SR971 
4K7R2J-2-GP 
1 2
SR978 
4K7R2J-2-GP 
1 2
C9321 
SCD1U25V3KX-GP 
1 2
SR988 
4K7R2J-2-GP 
1 2
SR970 
4K7R2J-2-GP 
1 2
SR1156 
4K7R2F-GP 
NOPOP 1 2
SR985 
4K7R2J-2-GP 
1 2
SR968 
4K7R2J-2-GP 
1 2
SR1047 
4K7R2F-GP 
1 2
SR1050 
4K7R2F-GP 
1 2
SR981 
4K7R2J-2-GP 
1 2
SR1151 
4K7R2F-GP 
NOPOP 1 2
SR966 
4K7R2J-2-GP 
1 2
SR973 
4K7R2J-2-GP 
1 2
SR1052 
4K7R2F-GP 
1 2
SR977 
4K7R2J-2-GP 
1 2
SR983 
4K7R2J-2-GP 
1 2
SR964 
4K7R2J-2-GP 
1 2
SR1049 
4K7R2F-GP 
1 2
EU16 
PCA9547BS-GP 
VSS 9
A2 18 
VDD 21 
A0 22 
A1 23 
GND 25 
SC0 2
SC1 4
SC2 6
SC3 8
SC4 11 
SC5 13 
SC6 15 
SC7 17 
SD0 1
SD1 3
SD2 5
SD3 7
SD4 10 
SD5 12 
SD6 14 
SD7 16 
SCL 19 
SDA 20 
RESET# 24 
SR1051 
4K7R2F-GP 
1 2
SR990 
4K7R2J-2-GP 
1 2
R429 0R2J-2-GP 1 2
PR9048 
0R2J-2-GP 
1 2
SR975 
4K7R2J-2-GP 
1 2
SR992 
4K7R2J-2-GP 
1 2
SR1152 
4K7R2F-GP 
NOPOP 1 2
SR969 
4K7R2J-2-GP 
1 2
SR1154 
4K7R2F-GP 
NOPOP 1 2



5
5
4
4
3
3
2
2
1
1
D D
C C
B B
A A
I2C Address:0xCA 
I2C Address:0xD8 
Ferrite Bead 
Ferrite Bead 
I2C_CLK BUFFER1-2 
1U 
0402 
X6S 
1U 
0402 
X6S 
1U 
0402 
X6S 
1U 
0402 
X6S 
10U 
0603 
X5R 
10U 
0603 
X5R 
Input Cap: 5pF 
Input Cap: 5pF 
0.1U 
0402 
X7R 
0.1U 
0402 
X7R 
0.1U 
0402 
X7R 
0.1U 
0402 
X7R 
0.1U 
0402 
X7R 
0.1U 
0402 
X7R 
0.1U 
0402 
X7R 
0.1U 
0402 
X7R 
0.1U 
0402 
X7R 
0.1U 
0402 
X7R 
0.1U 
0402 
X7R 
0.1U 
0402 
X7R 
0.1U 
0402 
X7R 
0.1U 
0402 
X7R 
0.1U 
0402 
X7R 
0.1U 
0402 
X7R 
0.1U 
0402 
X7R 
0.1U 
0402 
X7R 
CLK_BUF_EU2_SMB_A0_TRI 
CLK_BUF_EU2_SMB_A1_TRI 
CLK_BUF_EU2_100M_133M# 
CLK_BUF_EU2_HIBW_BYPM_LOBW# 
CLK_BUF_EU1_100M_133M# 
CLK_BUF_EU1_SMB_A0_TRI 
CLK_BUF_EU1_HIBW_BYPM_LOBW# 
CLK_BUF_EU1_SMB_A1_TRI 
PE_CLK_100M_DR0_1_R_P 
PE_CLK_100M_DR10_1_R_P 
PE_CLK_100M_DR0_2_R_N 
PE_CLK_100M_DR0_1_R_N 
PE_CLK_100M_DR10_2_R_N 
PE_CLK_100M_DR10_1_R_N 
PE_CLK_100M_DR0_2_R_P 
PE_CLK_100M_DR10_2_R_P 
PE_CLK_100M_DR2_2_R_N 
PE_CLK_100M_DR2_1_R_N 
PE_CLK_100M_DR2_2_R_P 
PE_CLK_100M_DR2_1_R_P 
PE_CLK_100M_DR1_2_R_N 
PE_CLK_100M_DR1_1_R_N 
PE_CLK_100M_DR1_2_R_P 
PE_CLK_100M_DR1_1_R_P 
PE_CLK_100M_DR5_2_R_P 
PE_CLK_100M_DR5_1_R_P 
PE_CLK_100M_DR5_2_R_N 
PE_CLK_100M_DR5_1_R_N 
CLK_BUFFER_EU1_VOE_N 
PE_CLK_100M_DR6_2_R_N 
PE_CLK_100M_DR6_1_R_N 
PE_CLK_100M_DR6_2_R_P 
PE_CLK_100M_DR6_1_R_P 
PE_CLK_100M_DR11_2_R_P 
PE_CLK_100M_DR11_1_R_P 
PE_CLK_100M_DR11_2_R_N 
PE_CLK_100M_DR11_1_R_N 
CLK_BUFFER_EU2_VOE_N 
I2C_SCL_BUF_9_EU1_R 
I2C_SDA_BUF_9_EU1_R 
I2C_SCL_BUF_9_EU2_R 
I2C_SDA_BUF_9_EU2_R 
PE_100M_CLK4_p 
PE_100M_CLK4_n 
PE_100M_CLK3_n 
PE_100M_CLK3_p 
VDD_DIFF_2 VDD_IO_2 
VDD_DIFF_2 
VDD_DIFF_2 VDD_DIFF_2 VDD_DIFF_2 
VDD_DIFF_1 
VDD_DIFF_1 VDD_IO_1 
VDD_DIFF_1 VDD_DIFF_1 VDD_DIFF_1 
P3V3 
P3V3 
VDDR_1 VDDA_1 
P3V3 
VDD_IO_1 
P3V3 
VDDA_1 
VDDR_1 
VDD_DIFF_1 
VDD_IO_2 
P3V3 
P3V3 
VDDA_2 
VDDR_2 
VDD_DIFF_2 
VDDA_2 VDDR_2 
VDD_DIFF_1 VDD_DIFF_1 
VDD_DIFF_2 VDD_DIFF_2 
BMC_I2C_SDA_BUF_9 16,19,20,21 
BMC_I2C_SCL_BUF_9 16,19,20,21 
PE_100M_CLK3_p 16 
PE_100M_CLK3_n 16 
BMC_I2C_SDA_BUF_9 16,19,20,21 
BMC_I2C_SCL_BUF_9 16,19,20,21 
SSD_PRSNT2 9
SSD2_CLK0_OE_R_n 9,16 
SSD_PRSNT0 8
SSD0_CLK0_OE_R_n 8,16 
SSD_PRSNT10 13 
SSD10_CLK0_OE_R_n 13,16 
PE_CLK100M_dr0_1_p 8
PE_CLK100M_dr10_1_p 13 
PE_CLK100M_dr0_2_n 8
PE_CLK100M_dr0_1_n 8
PE_CLK100M_dr10_2_n 13 
PE_CLK100M_dr10_1_n 13 
PE_CLK100M_dr0_2_p 8
PE_CLK100M_dr10_2_p 13 
PE_CLK100M_dr2_2_n 9
PE_CLK100M_dr2_1_n 9
PE_CLK100M_dr2_2_p 9
PE_CLK100M_dr2_1_p 9
PE_CLK100M_dr1_2_n 8
PE_CLK100M_dr1_1_n 8
PE_CLK100M_dr1_2_p 8
PE_CLK100M_dr1_1_p 8
SSD_PRSNT1 8
SSD1_CLK0_OE_R_n 8,16 
P3V3_PG 21,22,23 
P3V3_PG 21,22,23 
PE_CLK100M_dr5_2_p 10 
PE_CLK100M_dr5_1_p 10 
PE_CLK100M_dr5_2_n 10 
PE_CLK100M_dr5_1_n 10 
SSD_PRSNT5 10 
SSD5_CLK0_OE_R_n 10,16 
PE_CLK100M_dr6_2_n 11 
PE_CLK100M_dr6_1_n 11 
PE_CLK100M_dr6_2_p 11 
PE_CLK100M_dr6_1_p 11 
PE_CLK100M_dr11_2_p 13 
PE_CLK100M_dr11_1_p 13 
PE_CLK100M_dr11_2_n 13 
PE_CLK100M_dr11_1_n 13 
SSD_PRSNT6 11 
SSD6_CLK0_OE_R_n 11,16 
SSD11_CLK0_OE_R_n 13,16 
SSD_PRSNT11 13 
PE_100M_CLK4_p 16 
PE_100M_CLK4_n 16 
Title 
Size Document Number Rev 
Date: Sheet 
of 
Lightning_PDPB 1
I2C CLK BUFFER 1 
C
21 28 Thursday, March 09, 2017 
Wiwynn 
H/W R&D Dept. II 
8F,90,Sec. 1,Hsin Tai Wu Rd, 
Hsichih, Taipei Hsien 221, Taiwan, R.O.C 
Title 
Size Document Number Rev 
Date: Sheet 
of 
Lightning_PDPB 1
I2C CLK BUFFER 1 
C
21 28 Thursday, March 09, 2017 
Wiwynn 
H/W R&D Dept. II 
8F,90,Sec. 1,Hsin Tai Wu Rd, 
Hsichih, Taipei Hsien 221, Taiwan, R.O.C 
Title 
Size Document Number Rev 
Date: Sheet 
of 
Lightning_PDPB 1
I2C CLK BUFFER 1 
C
21 28 Thursday, March 09, 2017 
Wiwynn 
H/W R&D Dept. II 
8F,90,Sec. 1,Hsin Tai Wu Rd, 
Hsichih, Taipei Hsien 221, Taiwan, R.O.C 
R9349 
2D2R2F-GP 
1 2
C8849 
SCD1U16V2KX-3GP 
1 2
R9075 27R2F-GP 1 2
R9058 27R2F-GP 1 2
R9103 27R2F-GP 1 2
C8914 
SC10U25V3MX-GP 
1 2
R9965 
1KR2J-1-GP 
1 2
R9070 27R2F-GP 1 2
C8850 
SCD1U16V2KX-3GP 
1 2
R9352 
2D2R2F-GP 
1 2
R9073 27R2F-GP 1 2
C8896 
SCD1U16V2KX-3GP 
1 2
R9957 
5K6R2F-2-GP 
1 2
R9511 
4K7R2F-GP 
1 2
R9055 27R2F-GP 1 2
R9066 27R2F-GP 1 2
C8837 
SCD1U16V2KX-3GP 
1 2
R420 0R2J-2-GP 1 2
R9079 27R2F-GP 1 2
PR9038 
4K7R2F-GP 
NOPOP 
1 2
C9424 
SCD1U16V2KX-3GP 
1 2
R9093 
4K7R2F-GP 
1 2
SR947 
4K7R2F-GP 
1 2
R9056 27R2F-GP 1 2
C8909 
SC1U10V2KX-7-GP 
1 2
C8897 
SC10U25V3MX-GP 
1 2
R9067 27R2F-GP 1 2
C8838 
SCD1U16V2KX-3GP 
1 2
C8910 
SCD1U16V2KX-3GP 
1 2
R9034 
4K7R2F-GP 
1 2
PR9009 
4K7R2F-GP 
NOPOP 
1 2
FB6 
BLM21PG331SN1D-2-GP 
1 2
R9068 27R2F-GP 1 2
C9515 
SCD1U16V2KX-3GP 
1 2
R9064 27R2F-GP 1 2
R9065 27R2F-GP 1 2
R9077 27R2F-GP 1 2
SR946 
4K7R2F-GP 
NOPOP 
1 2
SR945 
4K7R2F-GP 
1 2
C8839 
SCD1U16V2KX-3GP 
1 2
C9514 
SCD1U16V2KX-3GP 
1 2
R9963 
5K6R2F-2-GP 
1 2
R9071 27R2F-GP 1 2
R9078 27R2F-GP 1 2
C9418 
SCD1U16V2KX-3GP 
1 2
R9057 27R2F-GP 1 2
C8840 
SCD1U16V2KX-3GP 
1 2
R9092 
4K7R2F-GP 
1 2
R9074 27R2F-GP 1 2
R9099 27R2F-GP 1 2
R9350 
2D2R2F-GP 
1 2
EU2 
9ZXL1231AKLFT-GP 
VDDA 1
VDDR 8
SMBDAT 12 SMBCLK 13 
DFB_OUT_NC# 15 DFB_OUT_NC 16 
DIF_1 21 
DIF_1# 22 
DIF_2 26 
DIF_2# 27 
DIF_3 30 
DIF_3# 31 
DIF_4 34 
DIF_4# 35 
DIF_5 38 
DIF_5# 39 
DIF_6 42 
DIF_6# 43 
DIF_7 46 
DIF_7# 47 
DIF_8 50 
DIF_8# 51 
DIF_9 54 
DIF_9# 55 
DIF_10 59 
DIF_10# 60 
DIF_11 63 
DIF_11# 64 
THERMAL_BASE 65 
NC#3 3
VDD 24 
VDD 40 
VDD 57 
VDDIO 25 
VDDIO 32 
VDDIO 49 
VDDIO 56 
DIF_IN 9
DIF_IN# 10 
100M_133M# 4
HIBW_BYPM_LOBW# 5
CKPWRGD_PD# 6
SMB_A0_TRI 11 
SMB_A1_TRI 14 
VOE0# 19 
VOE1# 20 
VOE2# 28 
VOE3# 29 
VOE4# 36 
VOE5# 37 
VOE6# 44 
VOE7# 45 
VOE8# 52 
VOE9# 53 
VOE10# 61 
VOE11# 62 
GNDA 2
GND 7
GND 23 
GND 33 
GND 41 
GND 48 
GND 58 
DIF_0 17 
DIF_0# 18 
SR950 
4K7R2F-GP 
1 2
R9512 
4K7R2F-GP 
1 2
R9033 
4K7R2F-GP 
1 2
PR9008 
4K7R2F-GP 
NOPOP 
1 2
R9101 27R2F-GP 1 2
R9958 
1KR2J-1-GP 
1 2
R421 0R2J-2-GP 1 2
R9583 
0R5J-L1-GP 
1 2
C8895 
SC1U10V2KX-7-GP 
1 2
C9419 
SCD1U16V2KX-3GP 
1 2
R9076 27R2F-GP 1 2
R9063 27R2F-GP 1 2
R9069 27R2F-GP 1 2
R9966 
1KR2J-1-GP 
1 2
EU1 
9ZXL1231AKLFT-GP 
VDDA 1
VDDR 8
SMBDAT 12 SMBCLK 13 
DFB_OUT_NC# 15 DFB_OUT_NC 16 
DIF_1 21 
DIF_1# 22 
DIF_2 26 
DIF_2# 27 
DIF_3 30 
DIF_3# 31 
DIF_4 34 
DIF_4# 35 
DIF_5 38 
DIF_5# 39 
DIF_6 42 
DIF_6# 43 
DIF_7 46 
DIF_7# 47 
DIF_8 50 
DIF_8# 51 
DIF_9 54 
DIF_9# 55 
DIF_10 59 
DIF_10# 60 
DIF_11 63 
DIF_11# 64 
THERMAL_BASE 65 
NC#3 3
VDD 24 
VDD 40 
VDD 57 
VDDIO 25 
VDDIO 32 
VDDIO 49 
VDDIO 56 
DIF_IN 9
DIF_IN# 10 
100M_133M# 4
HIBW_BYPM_LOBW# 5
CKPWRGD_PD# 6
SMB_A0_TRI 11 
SMB_A1_TRI 14 
VOE0# 19 
VOE1# 20 
VOE2# 28 
VOE3# 29 
VOE4# 36 
VOE5# 37 
VOE6# 44 
VOE7# 45 
VOE8# 52 
VOE9# 53 
VOE10# 61 
VOE11# 62 
GNDA 2
GND 7
GND 23 
GND 33 
GND 41 
GND 48 
GND 58 
DIF_0 17 
DIF_0# 18 
C8894 
SCD1U16V2KX-3GP 
1 2
R9960 
5K6R2F-2-GP 
1 2
C8912 
SCD1U16V2KX-3GP 
1 2
R9351 
2D2R2F-GP 
1 2
SR949 
4K7R2F-GP 
NOPOP 
1 2
R9964 
100R1F-GP NOPOP 
1 2
R9104 27R2F-GP 1 2
SR948 
4K7R2F-GP 
1 2
R9962 
5K6R2F-2-GP 
1 2
C8851 
SCD1U16V2KX-3GP 
1 2
R422 0R2J-2-GP 1 2
PR9061 
1K4R2F-1-GP 
NOPOP 
1 2
C8911 
SC1U10V2KX-7-GP 
1 2
R9100 27R2F-GP 1 2
R9959 
100R1F-GP NOPOP 
1 2
PR9062 
1K4R2F-1-GP 
NOPOP 
1 2
R9037 
4K7R2F-GP 
NOPOP 
1 2
R9072 27R2F-GP 1 2
FB7 
BLM21PG331SN1D-2-GP 
1 2
R9097 27R2F-GP 1 2
R9102 27R2F-GP 1 2
C8852 
SCD1U16V2KX-3GP 
1 2
R9961 
1KR2J-1-GP 
1 2
R419 0R2J-2-GP 1 2
C8893 
SC1U10V2KX-7-GP 
1 2
C9425 
SCD1U16V2KX-3GP 
1 2
R9582 
0R5J-L1-GP 
1 2



5
5
4
4
3
3
2
2
1
1
D D
C C
B B
A A
I2C Address:0xDE 
I2C Address:0xCE 
Ferrite Bead 
Ferrite Bead 
I2C_CLK BUFFER3-4 
1U 
0402 
X6S 
1U 
0402 
X6S 
1U 
0402 
X6S 
1U 
0402 
X6S 
10U 
0603 
X5R 
10U 
0603 
X5R 
Input Cap: 5pF 
Input Cap: 5pF 
0.1U 
0402 
X7R 
0.1U 
0402 
X7R 
0.1U 
0402 
X7R 
0.1U 
0402 
X7R 
0.1U 
0402 
X7R 
0.1U 
0402 
X7R 
0.1U 
0402 
X7R 
0.1U 
0402 
X7R 
0.1U 
0402 
X7R 
0.1U 
0402 
X7R 
0.1U 
0402 
X7R 
0.1U 
0402 
X7R 
0.1U 
0402 
X7R 
0.1U 
0402 
X7R 
0.1U 
0402 
X7R 
0.1U 
0402 
X7R 
0.1U 
0402 
X7R 
0.1U 
0402 
X7R 
CLK_BUF_EU3_100M_133M# 
CLK_BUF_EU3_SMB_A0_TRI 
CLK_BUF_EU3_HIBW_BYPM_LOBW# 
CLK_BUF_EU3_SMB_A1_TRI 
CLK_BUF_EU4_100M_133M# 
CLK_BUF_EU4_SMB_A0_TRI 
CLK_BUF_EU4_HIBW_BYPM_LOBW# 
PE_CLK_100M_DR9_2_R_N 
PE_CLK_100M_DR9_1_R_N 
PE_CLK_100M_DR9_2_R_P 
PE_CLK_100M_DR14_2_R_N 
PE_CLK_100M_DR14_1_R_N 
PE_CLK_100M_DR9_1_R_P 
PE_CLK_100M_DR14_2_R_P 
PE_CLK_100M_DR14_1_R_P 
PE_CLK_100M_DR3_1_R_P 
PE_CLK_100M_DR4_2_R_N 
PE_CLK_100M_DR4_1_R_N 
PE_CLK_100M_DR3_2_R_N 
PE_CLK_100M_DR4_2_R_P 
PE_CLK_100M_DR3_1_R_N 
PE_CLK_100M_DR4_1_R_P 
PE_CLK_100M_DR3_2_R_P 
CLK_BUF_EU4_SMB_A1_TRI 
CLK_BUFFER_EU4_VOE_N 
PE_CLK_100M_DR13_2_R_N 
PE_CLK_100M_DR13_1_R_N 
PE_CLK_100M_DR13_2_R_P 
PE_CLK_100M_DR13_1_R_P 
PE_CLK_100M_DR8_2_R_P 
PE_CLK_100M_DR8_2_R_N 
PE_CLK_100M_DR8_1_R_N 
PE_CLK_100M_DR8_1_R_P 
PE_CLK_100M_DR7_1_R_P 
PE_CLK_100M_DR7_2_R_N 
PE_CLK_100M_DR7_1_R_N 
PE_CLK_100M_DR7_2_R_P 
PE_CLK_100M_DR12_1_R_N 
PE_CLK_100M_DR12_2_R_P 
PE_CLK_100M_DR12_1_R_P 
PE_CLK_100M_DR12_2_R_N 
CLK_BUFFER_EU3_VOE_N 
I2C_SCL_BUF_8_EU3_R 
I2C_SDA_BUF_8_EU3_R 
I2C_SCL_BUF_8_EU4_R 
I2C_SDA_BUF_8_EU4_R 
PE_100M_CLK2_n 
PE_100M_CLK2_p 
PE_100M_CLK1_n 
PE_100M_CLK1_p 
VDD_DIFF_3 
VDD_DIFF_3 VDD_IO_3 VDD_DIFF_3 VDD_DIFF_3 VDD_DIFF_3 
P3V3 
P3V3 
VDD_DIFF_4 
VDD_DIFF_4 VDD_IO_4 VDD_DIFF_4 VDD_DIFF_4 VDD_DIFF_4 
VDD_IO_3 
P3V3 
P3V3 
VDDA_3 
VDDR_3 
VDD_DIFF_3 
VDDR_3 VDDA_3 
VDD_IO_4 
P3V3 
P3V3 
VDDA_4 
VDDR_4 
VDD_DIFF_4 
VDDA_4 VDDR_4 
VDD_DIFF_3 VDD_DIFF_3 
VDD_DIFF_4 VDD_DIFF_4 
PE_100M_CLK2_p 16 
PE_100M_CLK2_n 16 
BMC_I2C_SDA_BUF_8 16,19,20,22 
BMC_I2C_SCL_BUF_8 16,19,20,22 
PE_100M_CLK1_p 16 
PE_100M_CLK1_n 16 
BMC_I2C_SDA_BUF_8 16,19,20,22 
BMC_I2C_SCL_BUF_8 16,19,20,22 
PE_CLK100M_dr9_2_n 12 
SSD_PRSNT9 12 
PE_CLK100M_dr9_1_n 12 
PE_CLK100M_dr9_2_p 12 
SSD9_CLK0_OE_R_n 12,17 
PE_CLK100M_dr14_2_n 15 
SSD_PRSNT14 15 
PE_CLK100M_dr14_1_n 15 
PE_CLK100M_dr9_1_p 12 
SSD14_CLK0_OE_R_n 15,17 
PE_CLK100M_dr14_2_p 15 
PE_CLK100M_dr14_1_p 15 
SSD_PRSNT4 10 
SSD4_CLK0_OE_R_n 10,17 
SSD_PRSNT3 9
SSD3_CLK0_OE_R_n 9,16 
PE_CLK100M_dr3_1_p 9
PE_CLK100M_dr4_2_n 10 
PE_CLK100M_dr4_1_n 10 
PE_CLK100M_dr3_2_n 9
PE_CLK100M_dr4_2_p 10 
PE_CLK100M_dr3_1_n 9
PE_CLK100M_dr4_1_p 10 
PE_CLK100M_dr3_2_p 9
P3V3_PG 21,22,23 
P3V3_PG 21,22,23 
PE_CLK100M_dr13_2_n 14 
PE_CLK100M_dr13_1_n 14 
PE_CLK100M_dr13_2_p 14 
PE_CLK100M_dr13_1_p 14 
PE_CLK100M_dr8_2_p 12 
PE_CLK100M_dr8_2_n 12 
PE_CLK100M_dr8_1_n 12 
PE_CLK100M_dr8_1_p 12 
SSD8_CLK0_OE_R_n 12,17 
SSD_PRSNT13 14 
SSD13_CLK0_OE_R_n 14,17 
SSD_PRSNT8 12 
PE_CLK100M_dr7_1_p 11 
PE_CLK100M_dr7_2_n 11 
PE_CLK100M_dr7_1_n 11 
PE_CLK100M_dr7_2_p 11 
PE_CLK100M_dr12_2_n 14 
PE_CLK100M_dr12_1_n 14 
PE_CLK100M_dr12_2_p 14 
PE_CLK100M_dr12_1_p 14 
SSD_PRSNT7 11 
SSD7_CLK0_OE_R_n 11,16 
SSD_PRSNT12 14 
SSD12_CLK0_OE_R_n 14,16 
Title 
Size Document Number Rev 
Date: Sheet 
of 
Lightning_PDPB 1
I2C CLK BUFFER 2 
C
22 28 Thursday, March 09, 2017 
Wiwynn 
H/W R&D Dept. II 
8F,90,Sec. 1,Hsin Tai Wu Rd, 
Hsichih, Taipei Hsien 221, Taiwan, R.O.C 
Title 
Size Document Number Rev 
Date: Sheet 
of 
Lightning_PDPB 1
I2C CLK BUFFER 2 
C
22 28 Thursday, March 09, 2017 
Wiwynn 
H/W R&D Dept. II 
8F,90,Sec. 1,Hsin Tai Wu Rd, 
Hsichih, Taipei Hsien 221, Taiwan, R.O.C 
Title 
Size Document Number Rev 
Date: Sheet 
of 
Lightning_PDPB 1
I2C CLK BUFFER 2 
C
22 28 Thursday, March 09, 2017 
Wiwynn 
H/W R&D Dept. II 
8F,90,Sec. 1,Hsin Tai Wu Rd, 
Hsichih, Taipei Hsien 221, Taiwan, R.O.C 
EU3 
9ZXL1231AKLFT-GP 
VDDA 1
VDDR 8
SMBDAT 12 SMBCLK 13 
DFB_OUT_NC# 15 DFB_OUT_NC 16 
DIF_1 21 
DIF_1# 22 
DIF_2 26 
DIF_2# 27 
DIF_3 30 
DIF_3# 31 
DIF_4 34 
DIF_4# 35 
DIF_5 38 
DIF_5# 39 
DIF_6 42 
DIF_6# 43 
DIF_7 46 
DIF_7# 47 
DIF_8 50 
DIF_8# 51 
DIF_9 54 
DIF_9# 55 
DIF_10 59 
DIF_10# 60 
DIF_11 63 
DIF_11# 64 
THERMAL_BASE 65 
NC#3 3
VDD 24 
VDD 40 
VDD 57 
VDDIO 25 
VDDIO 32 
VDDIO 49 
VDDIO 56 
DIF_IN 9
DIF_IN# 10 
100M_133M# 4
HIBW_BYPM_LOBW# 5
CKPWRGD_PD# 6
SMB_A0_TRI 11 
SMB_A1_TRI 14 
VOE0# 19 
VOE1# 20 
VOE2# 28 
VOE3# 29 
VOE4# 36 
VOE5# 37 
VOE6# 44 
VOE7# 45 
VOE8# 52 
VOE9# 53 
VOE10# 61 
VOE11# 62 
GNDA 2
GND 7
GND 23 
GND 33 
GND 41 
GND 48 
GND 58 
DIF_0 17 
DIF_0# 18 
SR954 
4K7R2F-GP 
1 2
R9968 
5K6R2F-2-GP 
1 2
R9129 27R2F-GP 1 2
C8935 
SC10U25V3MX-GP 
1 2
R9118 
4K7R2F-GP 
1 2
C9429 
SCD1U16V2KX-3GP 
1 2
R9098 27R2F-GP 1 2
SR955 
4K7R2F-GP 
1 2
R9972 
5K6R2F-2-GP 
1 2
PR9063 
1K4R2F-1-GP 
NOPOP 
1 2
R9976 
1KR2J-1-GP 
1 2
R9355 
2D2R2F-GP 
1 2
SR952 
4K7R2F-GP 
NOPOP 
1 2
R9060 27R2F-GP 1 2
FB9 
BLM21PG331SN1D-2-GP 
1 2
PR9039 
4K7R2F-GP 
NOPOP 
1 2
R9120 27R2F-GP 1 2
FB10 
BLM21PG331SN1D-2-GP 
1 2
C9433 
SCD1U16V2KX-3GP 
1 2
R9089 27R2F-GP 1 2
R9096 27R2F-GP 1 2
R9083 27R2F-GP 1 2
R9357 
2D2R2F-GP 
1 2
C9428 
SCD1U16V2KX-3GP 
1 2
R9086 27R2F-GP 1 2
C8862 
SCD1U16V2KX-3GP 
1 2
R9121 
4K7R2F-GP 
1 2
R9095 27R2F-GP 1 2
C9432 
SCD1U16V2KX-3GP 
1 2
R9356 
2D2R2F-GP 
1 2
R9091 27R2F-GP 1 2
R9358 
2D2R2F-GP 
1 2
C8864 
SCD1U16V2KX-3GP 
1 2 C8876 
SCD1U16V2KX-3GP 
1 2
PR9042 
4K7R2F-GP 
NOPOP 
1 2
R9084 27R2F-GP 1 2
C8931 
SC1U10V2KX-7-GP 
1 2
R9130 27R2F-GP 1 2
C8874 
SCD1U16V2KX-3GP 
1 2
R9088 27R2F-GP 1 2
C8861 
SCD1U16V2KX-3GP 
1 2
R9059 27R2F-GP 1 2
R9971 
1KR2J-1-GP 
1 2
R9125 27R2F-GP 1 2
R9082 27R2F-GP 1 2
C9516 
SCD1U16V2KX-3GP 
1 2
R9090 27R2F-GP 1 2
R9510 
4K7R2F-GP 
1 2
R9967 
5K6R2F-2-GP 
1 2
R9128 27R2F-GP 1 2
R423 0R2J-2-GP 1 2
R9061 27R2F-GP 1 2
C8916 
SC1U10V2KX-7-GP 
1 2
R9131 27R2F-GP 1 2
C8915 
SCD1U16V2KX-3GP 
1 2
C8873 
SCD1U16V2KX-3GP 
1 2
R9969 
100R1F-GP NOPOP 
1 2
R9975 
1KR2J-1-GP 
1 2
R9974 
100R1F-GP NOPOP 
1 2
C8863 
SCD1U16V2KX-3GP 
1 2
R425 0R2J-2-GP 1 2
PR9041 
4K7R2F-GP 
1 2
R9509 
4K7R2F-GP 
1 2
C8932 
SCD1U16V2KX-3GP 
1 2
R9081 27R2F-GP 1 2
C8875 
SCD1U16V2KX-3GP 
1 2
R9122 
4K7R2F-GP 
NOPOP 
1 2
R9973 
5K6R2F-2-GP 
1 2
SR951 
4K7R2F-GP 
1 2
R9126 27R2F-GP 1 2
R424 0R2J-2-GP 1 2
R9123 27R2F-GP 1 2
R9119 
4K7R2F-GP 
1 2
R9132 27R2F-GP 1 2
C8913 
SC1U10V2KX-7-GP 
1 2
R426 0R2J-2-GP 1 2
R9124 27R2F-GP 1 2
R9127 27R2F-GP 1 2
R9970 
1KR2J-1-GP 
1 2
PR9040 
4K7R2F-GP 
NOPOP 
1 2
R9133 27R2F-GP 1 2
R9085 27R2F-GP 1 2
C9517 
SCD1U16V2KX-3GP 
1 2
PR9064 
1K4R2F-1-GP 
NOPOP 
1 2
C8929 
SCD1U16V2KX-3GP 
1 2
EU4 
9ZXL1231AKLFT-GP 
VDDA 1
VDDR 8
SMBDAT 12 SMBCLK 13 
DFB_OUT_NC# 15 DFB_OUT_NC 16 
DIF_1 21 
DIF_1# 22 
DIF_2 26 
DIF_2# 27 
DIF_3 30 
DIF_3# 31 
DIF_4 34 
DIF_4# 35 
DIF_5 38 
DIF_5# 39 
DIF_6 42 
DIF_6# 43 
DIF_7 46 
DIF_7# 47 
DIF_8 50 
DIF_8# 51 
DIF_9 54 
DIF_9# 55 
DIF_10 59 
DIF_10# 60 
DIF_11 63 
DIF_11# 64 
THERMAL_BASE 65 
NC#3 3
VDD 24 
VDD 40 
VDD 57 
VDDIO 25 
VDDIO 32 
VDDIO 49 
VDDIO 56 
DIF_IN 9
DIF_IN# 10 
100M_133M# 4
HIBW_BYPM_LOBW# 5
CKPWRGD_PD# 6
SMB_A0_TRI 11 
SMB_A1_TRI 14 
VOE0# 19 
VOE1# 20 
VOE2# 28 
VOE3# 29 
VOE4# 36 
VOE5# 37 
VOE6# 44 
VOE7# 45 
VOE8# 52 
VOE9# 53 
VOE10# 61 
VOE11# 62 
GNDA 2
GND 7
GND 23 
GND 33 
GND 41 
GND 48 
GND 58 
DIF_0 17 
DIF_0# 18 
R9584 
0R5J-L1-GP 
1 2
C8934 
SCD1U16V2KX-3GP 
1 2
C8933 
SC1U10V2KX-7-GP 
1 2
R9080 27R2F-GP 1 2
R9585 
0R5J-L1-GP 
1 2
SR956 
4K7R2F-GP 
NOPOP 
1 2
R9062 27R2F-GP 1 2
C8930 
SC10U25V3MX-GP 
1 2
R9094 27R2F-GP 1 2
SR953 
4K7R2F-GP 
1 2
R9087 27R2F-GP 1 2



5
5
4
4
3
3
2
2
1
1
D D
C C
B B
A A
Power rail :P3V3 
Controller : TPS53312 (Fswitching=700KHz)
TDC :0.88584A 
MAX :0.88584A 
OCP=4.1A 
P3V3  SWITCHING TPS53312 
Vout=3.305 
SS=1.4ms 
FS=700KHz 
22U 
1206 
X6S 
2.2U 
0402 
X5R 
22U 
0805 
X6S 
22U 
0805 
X6S 
1U 
0402 
X6S 
22U 
1206 
X6S 
0.1U 
0402 
X7R 
47U 
0805 
X5R 
47U 
0805 
X5R 
P3V3_OUT P3V3_SW 
P3V3_SNB 
P3V3_VBST_RR 
P3V3_CC 
P3V3_VRG5 
P3V3_EN_R 
P3V3_VFB 
P3V3_VO P3V3_VBST 
P3V3_SS 
P3V3_VFB 
P3V3_CC 
P3V3_VFB_R 
P3V3_CC_R 
P3V3_VIN 
P3V3_VCC 
TPS53312_P3V3_PG 
P12V 
P3V3 
AGND_P3V3 
AGND_P3V3 
P12V 
AGND_P3V3 
AGND_P3V3 
AGND_P3V3 
P12V 
AGND_P3V3 
P3V3 
P3V3_PG 21,22 
Title 
Size Document Number Rev
Date: Sheet 
of 
Lightning_PDPB 1
P3V3_TPS53312 
A3 
23 28Thursday, March 09, 2017 
Wiwynn 
H/W R&D Dept. II 
8F,90,Sec. 1,Hsin Tai Wu Rd, 
Hsichih, Taipei Hsien 221, Taiwan, R.O.C
Title 
Size Document Number Rev
Date: Sheet 
of 
Lightning_PDPB 1
P3V3_TPS53312 
A3 
23 28Thursday, March 09, 2017 
Wiwynn 
H/W R&D Dept. II 
8F,90,Sec. 1,Hsin Tai Wu Rd, 
Hsichih, Taipei Hsien 221, Taiwan, R.O.C
Title 
Size Document Number Rev
Date: Sheet 
of 
Lightning_PDPB 1
P3V3_TPS53312 
A3 
23 28Thursday, March 09, 2017 
Wiwynn 
H/W R&D Dept. II 
8F,90,Sec. 1,Hsin Tai Wu Rd, 
Hsichih, Taipei Hsien 221, Taiwan, R.O.C
PC1286 
SC22U6D3V5MX-5-GP 
1 2
PR97 
10KR2F-2-GP 
1 2
PR9086 
0R6J-3-GP 
1 2
PR9085 
10R3F-GP 
1 2
PL2 
COIL-6D8UH-10-GP 
1 2
PC1274 
SCD1U50V3KX-GP 
12
PC1283 
SC1KP50V2KX-1GP 
1 2
PC1275 
SC2D2U16V2KX-GP 
1 2
PC1284 
SC22U25V6KX-GP-U 
1 2
PR9087
0R6J-3-GP
1 2
PR9077 
10KR2F-2-GP 
1 2
PR9088 
0R6J-3-GP 
1 2
PG3 
COPPER-CLOSE-GP-U 
1 2
PG4 
GAP-CLOSE-PWR-4-GP 
1 2
PC1281 
SC1U25V3KX-GP 
1 2
PC1259 
SCD1U25V2KX-2-GP 
1 2
PC1263 
SC1U16V3KX-5GP 
1 2
PU2 
TPS53312RGTR-GP 
74.53312.073 
VBST 12 
VIN#13 13 
SW#9 9
VREG5 2
PG 5
GND 4
SS 3
VFB 1
VO 16 
VCC 15 
EN 6 SW#10 10 
SW#11 11 
VIN#14 14 
PGND 7
PGND 8GND 17 
PC1285 
SC47U10V5MX-GP-U 
1 2
PC1288 SC1U10V2KX-7-GP 
NOPOP 
1 2
PR9079 
10KR2F-2-GP NOPOP 1 2
PC1276 
SC22U25V6KX-GP-U 
1 2
R9891 
15KR2F-GP 
NOPOP 1 2
PR9080 
0R2J-2-GP 
12
PC1279 
SC3300P50V2KX-1GP 
1 2
PR9081 0R2J-2-GP 12
PR9090 
33KR2F-2-GP 
1 2
PC1280 
SCD1U16V2KX-3GP 
1 2
PC1287 
SC2K2P50V3KX-GP 
NOPOP 
1 2
PR9083 
2D2R3-1-U-GP 
12
PR9091 
3D01R5F-GP 
NOPOP 
1 2
PC1273 
SCD1U50V3KX-GP 
12
R9756 
4K7R2F-GP 
1 2
PR96 
37K4R2F-1-GP 
1 2
PR9084 
2KR2F-3-GP 
1 2
R9234 
0R2J-2-GP 
1 2
PC1272 
SC22U6D3V5MX-5-GP 
1 2
PC1282 
SC47U10V5MX-GP-U 
1 2



5
5
4
4
3
3
2
2
1
1
D D
C C
B B
A A
SCREW HOLES ARE PTH 
SCREW& T-SLOT 
T-SLOT HOLE 
SCREW HOLE 
Title 
Size Document Number Rev
Date: Sheet 
of 
Lightning_PDPB 1
SCREWS 
A3 
24 28Thursday, March 09, 2017 
Wiwynn 
H/W R&D Dept. II 
8F,90,Sec. 1,Hsin Tai Wu Rd, 
Hsichih, Taipei Hsien 221, Taiwan, R.O.C
Title 
Size Document Number Rev
Date: Sheet 
of 
Lightning_PDPB 1
SCREWS 
A3 
24 28Thursday, March 09, 2017 
Wiwynn 
H/W R&D Dept. II 
8F,90,Sec. 1,Hsin Tai Wu Rd, 
Hsichih, Taipei Hsien 221, Taiwan, R.O.C
Title 
Size Document Number Rev
Date: Sheet 
of 
Lightning_PDPB 1
SCREWS 
A3 
24 28Thursday, March 09, 2017 
Wiwynn 
H/W R&D Dept. II 
8F,90,Sec. 1,Hsin Tai Wu Rd, 
Hsichih, Taipei Hsien 221, Taiwan, R.O.C
H3 
HOLE315R140-GP 
1
H6 
HOLE315R140-GP 
1
H9 
GEN276X162R197X296-6-F-A-GP 
1
2
3
4
5
6
H4 
GEN276X162R197X296-6-F-A-GP 
1
2
3
4
5
6
H5 
GEN276X162R197X296-6-F-A-GP 
1
2
3
4
5
6
H12 
GEN276X162R197X296-6-F-A-GP 
1
2
3
4
5
6
H1 
GEN276X162R197X296-6-F-A-GP 
1
2
3
4
5
6
H7 
GEN276X162R197X296-6-F-A-GP 
1
2
3
4
5
6
H10 
GEN276X162R197X296-6-F-A-GP 
1
2
3
4
5
6
H2 
GEN276X162R197X296-6-F-A-GP 
1
2
3
4
5
6
H13 
GEN276X162R197X296-6-F-A-GP 
1
2
3
4
5
6
H8 
GEN276X162R197X296-6-F-A-GP 
1
2
3
4
5
6
H11 
GEN276X162R197X296-6-F-A-GP 
1
2
3
4
5
6